G04 ================== begin FILE IDENTIFICATION RECORD ==================*
G04 Layout Name:  13130-1b.brd*
G04 Film Name:    L8*
G04 File Format:  Gerber RS274X*
G04 File Origin:  Cadence Allegro 16.5-S037*
G04 Origin Date:  Thu Nov 13 17:27:10 2014*
G04 *
G04 Layer:  VIA CLASS/L8*
G04 Layer:  PIN/L8*
G04 Layer:  ETCH/L8*
G04 Layer:  DRAWING FORMAT/LAYER_PCB_STORY*
G04 Layer:  DRAWING FORMAT/LAYER_L8*
G04 *
G04 Offset:    (0.00 0.00)*
G04 Mirror:    No*
G04 Mode:      Positive*
G04 Rotation:  0*
G04 FullContactRelief:  No*
G04 UndefLineWidth:     6.00*
G04 ================== end FILE IDENTIFICATION RECORD ====================*
%FSLAX35Y35*MOIN*%
%IR0*IPPOS*OFA0.00000B0.00000*MIA0B0*SFA1.00000B1.00000*%
%ADD11C,.02*%
%ADD14C,.022*%
%ADD15C,.06*%
%ADD13C,.017*%
%ADD10C,.028*%
%ADD12C,.056*%
%ADD16C,.01*%
%ADD17C,.012*%
%ADD18C,.04*%
%ADD19C,.025*%
%ADD20C,.004*%
%ADD21C,.006*%
%ADD22C,.008*%
%ADD23C,.0035*%
%ADD24C,.0045*%
%ADD25C,.0075*%
%ADD32C,.03204*%
%ADD28C,.05204*%
%ADD29C,.04404*%
%ADD30C,.02704*%
%ADD31C,.04604*%
%ADD33C,.06804*%
%ADD26C,.11004*%
%ADD27C,.15004*%
G75*
%LPD*%
G75*
G36*
G01X62000Y41000D02*
X61000Y42000D01*
Y58500D01*
X58500Y61000D01*
X5500D01*
X3001Y63499D01*
Y128001D01*
X4500Y129500D01*
X16000D01*
X17000Y128500D01*
Y117000D01*
X40000Y94000D01*
X41078D01*
X41116Y93983D01*
G03X42921Y94000I884J2017D01*
G01X44500D01*
X47500Y91000D01*
X53500D01*
X59000Y85500D01*
X59879D01*
X59917Y85483D01*
G03X61683I883J2017D01*
G01X61721Y85500D01*
X63000D01*
X76000Y72500D01*
Y42500D01*
X74500Y41000D01*
X62000D01*
G37*
G36*
G01X83000Y51500D02*
X77500Y57000D01*
Y59503D01*
G02X78154Y59812I400J0D01*
G03X79115Y59468I960J1167D01*
G01X82885D01*
G03X84387Y60810I0J1512D01*
G01X84396Y60894D01*
Y60989D01*
G03X82886Y62490I-1511J-10D01*
G01X79115D01*
G03X78154Y62146I-1J-1511D01*
G02X77500Y62455I-254J309D01*
G01Y65621D01*
G02X78177Y65910I400J0D01*
G03Y69090I1523J1590D01*
G02X77500Y69379I-277J289D01*
G01Y76500D01*
X58500Y95500D01*
X55913D01*
X55712Y95702D01*
X50298D01*
X44500Y101500D01*
Y104278D01*
X44507Y104304D01*
G03Y105696I-2507J696D01*
G01X44500Y105722D01*
Y109000D01*
X43500Y110000D01*
X26500D01*
X18500Y118000D01*
Y125298D01*
X30488D01*
X36288Y119498D01*
X42490D01*
X44590Y121598D01*
X51024D01*
G02X51404Y121076I-1J-400D01*
G03X55596I2096J-676D01*
G02X55976Y121598I381J122D01*
G01X65500D01*
G03X67119Y125292I0J2202D01*
G02X67272Y125938I294J272D01*
G03X64763Y126647I-772J2062D01*
G02X64447Y126002I-316J-245D01*
G01X42766D01*
X42622Y125858D01*
G02X42057Y125857I-283J282D01*
G03X38319Y124602I-1557J-1557D01*
G02X37640Y124374I-396J55D01*
G01X32312Y129702D01*
X18298D01*
X17000Y131000D01*
X4500D01*
X3001Y132499D01*
Y286501D01*
X4000Y287500D01*
X46000D01*
X58250Y275250D01*
Y270101D01*
G02X57842Y269702I-400J1D01*
G03X56244Y265942I-42J-2202D01*
G02Y265658I-141J-142D01*
G03X57435Y261929I1556J-1558D01*
G02X57651Y261251I-66J-395D01*
G01X54900Y258500D01*
X39500D01*
X38500Y259500D01*
X36500D01*
X35500Y258500D01*
Y218500D01*
X37000Y217000D01*
X38500D01*
X39500Y218000D01*
X40500D01*
X41424Y217076D01*
Y214924D01*
X40679Y214179D01*
X40582Y214191D01*
G03X39500Y211498I-182J-1491D01*
G01Y209002D01*
G03X39275Y206805I900J-1202D01*
G02X39258Y206258I-300J-264D01*
G01X38116Y205116D01*
X38003Y205147D01*
G03X36153Y203297I-403J-1447D01*
G01X36184Y203184D01*
X36000Y203000D01*
Y198500D01*
X35112Y197612D01*
X34971Y197739D01*
G03X33754Y198287I-1470J-1639D01*
G02X33421Y198814I46J398D01*
G03X33502Y199336I-1421J488D01*
G01Y203164D01*
G03X30498I-1502J36D01*
G01Y199336D01*
G03X31464Y197897I1502J-36D01*
G02X31657Y197304I-142J-374D01*
G03X31546Y195084I1843J-1205D01*
G02X31191Y194500I-355J-184D01*
G01X20500D01*
X20000Y194000D01*
Y190692D01*
X19651D01*
X19609Y190835D01*
G03X19302Y191466I-2109J-636D01*
G01Y195254D01*
X26802Y202754D01*
Y257754D01*
X31246Y262198D01*
X35623D01*
G03Y265802I1877J1802D01*
G01X29754D01*
X23198Y259246D01*
Y204246D01*
X15698Y196746D01*
Y191466D01*
G03X19277Y188900I1802J-1266D01*
G02X20000Y188664I323J-236D01*
G01Y172500D01*
X21000Y171500D01*
X33500D01*
X42000Y163000D01*
X49500D01*
X54000Y167500D01*
X62553D01*
X62830Y167224D01*
X86776D01*
X89000Y165000D01*
Y158000D01*
X110000Y137000D01*
Y131037D01*
X109998Y131035D01*
Y75601D01*
X110000Y75599D01*
Y69046D01*
G03X109175Y66335I1200J-1846D01*
G02X108929Y65797I-368J-157D01*
G03X108095Y62093I671J-2097D01*
G02X108110Y61524I-273J-292D01*
G03X109615Y57800I1590J-1524D01*
G02X110000Y57400I-15J-400D01*
G01Y54000D01*
X107500Y51500D01*
X83000D01*
G37*
G36*
G01X65500Y235000D02*
Y246056D01*
G03X65876Y247002I-1000J945D01*
G01Y248070D01*
X65500Y248447D01*
Y263500D01*
X68000Y266000D01*
X72500D01*
X81998Y275498D01*
X171650D01*
X180075Y267074D01*
X247425D01*
X255000Y259498D01*
Y248500D01*
X253000Y246500D01*
X224500D01*
X222500Y244500D01*
Y223500D01*
X221000Y222000D01*
X208000D01*
X206000Y220000D01*
X131000D01*
X125000Y214000D01*
X113500D01*
X104000Y223500D01*
X99500D01*
X94118Y218118D01*
G03X93932Y218000I1085J-1916D01*
G01X77500D01*
X68000Y227500D01*
Y232500D01*
X65500Y235000D01*
G37*
G36*
G01X132500Y165000D02*
X123000Y174500D01*
Y178500D01*
X124000Y179500D01*
X128000D01*
X135500Y187000D01*
X135986D01*
X136031Y186975D01*
G03X138213Y187000I1069J1925D01*
G01X152500D01*
X154000Y185500D01*
Y184000D01*
X147000Y177000D01*
Y166000D01*
X146000Y165000D01*
X132500D01*
G37*
G36*
G01X208500Y89500D02*
X204500Y85500D01*
X199900D01*
G03X197100I-1400J-1700D01*
G01X195500D01*
X195163Y85163D01*
X195022Y85301D01*
G03X191690Y85000I-1537J-1577D01*
G01X188500D01*
X187500Y86000D01*
Y88053D01*
X189049Y89602D01*
X189120Y89609D01*
G03X191087Y91544I-220J2191D01*
G02X191487Y91898I397J-46D01*
G03X193576Y93367I13J2202D01*
G01X193623Y93500D01*
X194721D01*
G03X198172Y95014I1268J1800D01*
G01X198181Y95081D01*
X198600Y95500D01*
X200888D01*
G03X204056Y95442I1612J1500D01*
G01X204114Y95500D01*
X204500D01*
X205000Y96000D01*
X224166D01*
G02X224525Y95423I0J-400D01*
G03X228545Y95266I1975J-973D01*
G02X228658Y95526I186J74D01*
G03X229952Y96920I-809J2048D01*
G01X229967Y96967D01*
X230448Y97448D01*
X230673D01*
G02X230969Y96780I0J-400D01*
G03X234231I1631J-1480D01*
G02X234527Y97448I296J268D01*
G01X238052D01*
X239368Y96132D01*
X239292Y95999D01*
G03X239399Y93633I1908J-1099D01*
G01X239496Y93496D01*
X236703Y90703D01*
X236625Y90701D01*
G03X234506Y88683I75J-2201D01*
G01X234490Y88500D01*
X215500D01*
X214500Y89500D01*
X208500D01*
G37*
G36*
G01X306853Y262000D02*
G02X306461Y262477I0J400D01*
G03X302339Y263901I-2161J423D01*
G02X301700Y263800I-356J182D01*
G01X300451Y265049D01*
G03X296003Y267306I-3640J-1663D01*
G01X295983Y267302D01*
X289126D01*
X287827Y268600D01*
X285900D01*
X276000Y278500D01*
Y282000D01*
X278000Y284000D01*
X282500D01*
X293500Y273000D01*
X293794D01*
X294258Y272536D01*
X305091D01*
X305555Y273000D01*
X306000D01*
X308500Y275500D01*
X314623D01*
G03X315963Y274642I1777J1300D01*
G01X316023Y274630D01*
X316954Y273698D01*
X324358D01*
X326702Y276042D01*
Y276699D01*
X330751Y280748D01*
X338252D01*
X339000Y280000D01*
Y277500D01*
X334588Y273088D01*
X334496Y273095D01*
G03X331705Y270304I-196J-2595D01*
G01X331712Y270212D01*
X328895Y267395D01*
G02X328226Y267574I-283J283D01*
G03X325526Y264874I-2126J-574D01*
G02X325705Y264205I-104J-386D01*
G01X323500Y262000D01*
X322966D01*
Y262318D01*
X323069Y262375D01*
G03X320442Y265856I-1069J1925D01*
G02X320158I-142J141D01*
G03X317096Y262692I-1558J-1556D01*
G02X316822Y262000I-274J-292D01*
G01X306853D01*
G37*
G36*
G01X343500Y66000D02*
X342238Y67262D01*
X342232Y67336D01*
G03X339836Y69732I-2594J-198D01*
G01X339762Y69738D01*
X338500Y71000D01*
Y72590D01*
G03Y75814I-1500J1612D01*
G01Y84500D01*
X342500Y88500D01*
Y106500D01*
X348500Y112500D01*
Y117000D01*
X351500Y120000D01*
Y137143D01*
G03X352134Y138081I-700J1157D01*
G01X352145Y138145D01*
X357500Y143500D01*
Y152500D01*
X360000Y155000D01*
Y157974D01*
G02X360674Y158265I400J0D01*
G03Y160235I926J985D01*
G02X360000Y160526I-274J291D01*
G01Y165000D01*
X363500Y168500D01*
Y172000D01*
X363250Y172250D01*
Y178250D01*
X367500Y182500D01*
X374000D01*
X375493Y181007D01*
G03X375500Y180990I1253J506D01*
G01Y178972D01*
X375493Y178947D01*
G03Y178253I1307J-347D01*
G01X375500Y178228D01*
Y178000D01*
X375743Y177757D01*
G03X375949Y177549I1058J842D01*
G01X375957Y177543D01*
X376128Y177372D01*
G02X376070Y176758I-283J-283D01*
G03X377948Y174880I760J-1118D01*
G02X378562Y174938I331J-225D01*
G01X379000Y174500D01*
Y172000D01*
X379145Y171855D01*
X379134Y171759D01*
G03X381824Y171723I1343J-154D01*
G01X381816Y171816D01*
X382000Y172000D01*
Y174500D01*
X383000Y175500D01*
X384859D01*
G02X385257Y175054I1J-400D01*
G03X387943I1343J-154D01*
G02X388341Y175500I397J46D01*
G01X394212D01*
X394224Y175313D01*
G03X396922I1349J87D01*
G01X396934Y175500D01*
X399000D01*
X400500Y174000D01*
Y171500D01*
X399500Y170500D01*
X391000D01*
X389000Y168500D01*
Y147621D01*
G03X390713Y145529I847J-1054D01*
G01X390854Y145646D01*
X391500Y145000D01*
X401000D01*
X401788Y144212D01*
X401799Y144149D01*
G03X402907Y143041I1333J225D01*
G01X402970Y143030D01*
X403500Y142500D01*
Y136000D01*
X402500Y135000D01*
X400321D01*
G03X398101Y133915I-869J-1036D01*
G02X397701Y133500I-400J-15D01*
G01X395500D01*
X390778Y128778D01*
X390652Y128834D01*
G03X390495Y128893I-553J-1234D01*
G02X390402Y129215I58J191D01*
G03X388395Y129174I-1022J885D01*
G02X388104Y128500I-291J-274D01*
G01X387114D01*
X387093Y128676D01*
G03X384398Y128486I-1343J-159D01*
G01X384400Y128400D01*
X383245Y127245D01*
G02X382652Y127277I-282J283D01*
G03X380750Y125375I-1052J-850D01*
G02X380782Y124782I-251J-311D01*
G01X380000Y124000D01*
Y110500D01*
X379000Y109500D01*
X375500D01*
X375000Y110000D01*
X364500D01*
X362500Y108000D01*
X359100D01*
X351400Y100300D01*
Y84100D01*
X364500Y71000D01*
Y68790D01*
G03Y68610I2200J-90D01*
G01Y67500D01*
X363000Y66000D01*
X343500D01*
G37*
G36*
G01X463200Y124848D02*
G03Y127552I0J1352D01*
G02X463000Y127752I0J200D01*
G01Y132151D01*
G02X463187Y132351I200J0D01*
G03X462137Y134648I-87J1349D01*
G01X462136D01*
X461994Y134506D01*
X461500Y135000D01*
X453500D01*
X445500Y127000D01*
X439406D01*
G02X439039Y127560I0J400D01*
G03X436561I-1239J540D01*
G02X436194Y127000I-367J-160D01*
G01X433500D01*
X432000Y125500D01*
X429974D01*
G02X429582Y125977I0J400D01*
G03X428491Y127567I-1327J259D01*
G02X428329Y127801I35J197D01*
G03X426764Y126719I-1329J249D01*
G02X426926Y126485I-35J-197D01*
G03X426928Y125977I1329J-249D01*
G02X426536Y125500I-392J-77D01*
G01X424006D01*
G02X423616Y125991I0J400D01*
G03X423640Y126479I-1316J309D01*
G02X423914Y126913I396J53D01*
G03X422160Y128021I-414J1287D01*
G02X421886Y127587I-396J-53D01*
G03X420957Y126459I414J-1287D01*
G02X420277Y126223I-397J47D01*
G01X419360Y127140D01*
X419491Y127281D01*
G03X417581Y129191I-991J919D01*
G01X417440Y129060D01*
X416012Y130488D01*
X416108Y130625D01*
G03X414095Y132405I-1108J776D01*
G01X404002Y142498D01*
Y142708D01*
X402500Y144209D01*
Y145000D01*
X403000Y145500D01*
X404000D01*
X405000Y146500D01*
Y147500D01*
X406411Y148911D01*
X406454Y148926D01*
G03X407274Y149746I-454J1274D01*
G01X407289Y149789D01*
X408723Y151223D01*
G02X409324Y151182I283J-283D01*
G03X411218Y153076I1076J818D01*
G02X411177Y153677I242J318D01*
G01X411500Y154000D01*
Y154227D01*
X411516Y154264D01*
G03X411609Y154994I-1244J529D01*
G01X411594Y155094D01*
X412500Y156000D01*
X414000D01*
X414500Y155500D01*
X414651D01*
G02X415050Y155077I0J-400D01*
G03X417750I1350J-77D01*
G02X418149Y155500I399J23D01*
G01X418808D01*
X418822Y155486D01*
X423783D01*
G02X424175Y155006I0J-400D01*
G03X426619Y153978I1325J-269D01*
G02X427281I331J-224D01*
G03X429725Y155006I1119J759D01*
G02X430117Y155486I392J80D01*
G01X432514D01*
X433500Y154500D01*
X437874D01*
G02X438268Y154032I0J-400D01*
G03X438253Y153922I1331J-238D01*
G02X437979Y153754I-199J17D01*
G03X438788Y152191I-507J-1253D01*
G02X439274Y152488I389J-91D01*
G03X440932Y154032I326J1312D01*
G02X441326Y154500I394J68D01*
G01X625500D01*
X625550Y154550D01*
X628601Y156833D01*
X628683Y156821D01*
G03X631180Y158689I317J2179D01*
G01X631192Y158771D01*
X632700Y159900D01*
X641709Y167829D01*
X654060Y176745D01*
X658000Y179000D01*
X681615Y190615D01*
X699500Y208500D01*
X715000D01*
X717000Y206500D01*
Y205000D01*
X712000Y200000D01*
X707500D01*
X706720Y199220D01*
X705735D01*
X692474Y185959D01*
Y170339D01*
X663414Y141279D01*
Y126360D01*
X655430Y118376D01*
X646664D01*
X633464Y131576D01*
X614130D01*
X606984Y124430D01*
Y123519D01*
G03X609931Y120257I1376J-1719D01*
G02X610509Y120249I285J-280D01*
G03X613565Y123411I1611J1501D01*
G01X613496Y123471D01*
Y123930D01*
X616190Y126624D01*
X618860D01*
G02X619204Y126020I0J-400D01*
G03X622996I1896J-1120D01*
G02X623340Y126624I344J204D01*
G01X631130D01*
X644130Y113624D01*
X657570D01*
X668256Y124310D01*
Y139550D01*
X697076Y168370D01*
Y183990D01*
X697432Y184346D01*
G02X698115Y184063I283J-283D01*
G01Y183385D01*
X703000Y178500D01*
Y103000D01*
X706051Y99949D01*
G02X705989Y99333I-283J-283D01*
G03X705354Y96314I1220J-1833D01*
G02X705036Y95699I-337J-215D01*
G03X707000Y94686I109J-2199D01*
G02X707318Y95301I337J215D01*
G03X709042Y96280I-109J2199D01*
G02X709658Y96342I333J-221D01*
G01X725000Y81000D01*
Y58500D01*
X746000Y37500D01*
Y30000D01*
X744000Y28000D01*
Y23946D01*
G03X743952Y22107I1000J-946D01*
G01X744000Y22051D01*
Y21542D01*
G03X743524Y20500I900J-1041D01*
G01Y14530D01*
X746500Y11553D01*
Y5500D01*
X744000Y3000D01*
X455500D01*
X454500Y4000D01*
Y8500D01*
X456000Y10000D01*
X501898D01*
X502892Y9006D01*
X511222D01*
X512216Y10000D01*
X530500D01*
X532000Y11500D01*
Y15035D01*
X532007Y15060D01*
G03Y15754I-1307J347D01*
G01X532000Y15779D01*
Y16000D01*
X531781Y16219D01*
X531773Y16229D01*
G03X531522Y16480I-1073J-822D01*
G01X531512Y16488D01*
X531000Y17000D01*
Y29335D01*
G02X531617Y29671I400J0D01*
G03Y31943I733J1136D01*
G02X531000Y32279I-217J336D01*
G01Y40000D01*
X534000Y43000D01*
X593000D01*
X600674Y35326D01*
Y27904D01*
X601000Y27577D01*
Y27000D01*
X604078Y23922D01*
X603958Y23782D01*
G03X605864Y21876I1031J-875D01*
G01X606004Y21996D01*
X610647Y17353D01*
X610654Y17281D01*
G03X611874Y16061I1346J126D01*
G01X611946Y16054D01*
X612500Y15500D01*
Y13500D01*
X615500Y10500D01*
X666500D01*
X668000Y12000D01*
Y14000D01*
X671000Y17000D01*
Y31441D01*
G02X671376Y31840I400J0D01*
G03Y34540I-81J1350D01*
G02X671000Y34939I24J399D01*
G01Y40000D01*
X672000Y41000D01*
Y60000D01*
X644694Y87306D01*
X644764Y87437D01*
G03X643046Y90668I-1941J1040D01*
G02X642867Y90887I20J199D01*
G03X641020Y93290I-2190J228D01*
G02X640686Y93734I63J395D01*
G03X636971Y95585I-2186J266D01*
G02X636410Y95590I-278J287D01*
G01X635787Y96213D01*
G03X633367Y99609I-1787J1287D01*
G02X632860Y100070I-115J383D01*
G03X629721Y102472I-2160J430D01*
G01X629592Y102408D01*
X626227Y105773D01*
X626355Y105914D01*
G03X623245Y109024I-1629J1481D01*
G01X623104Y108896D01*
X614500Y117500D01*
X538452D01*
G02X538136Y118146I0J400D01*
G03X534842Y121056I-1737J1353D01*
G02X534558I-142J141D01*
G03X531264Y118146I-1557J-1557D01*
G02X530948Y117500I-316J-246D01*
G01X530152D01*
G02X529836Y118146I0J400D01*
G03X526364I-1736J1354D01*
G02X526048Y117500I-316J-246D01*
G01X513552D01*
G02X513236Y118146I0J400D01*
G03X510019Y121130I-1736J1354D01*
G02X509481I-269J296D01*
G03X506264Y118146I-1481J-1630D01*
G02X505948Y117500I-316J-246D01*
G01X495194D01*
G02X494857Y118115I0J400D01*
G03X491143I-1857J1184D01*
G02X490806Y117500I-337J-215D01*
G01X468000D01*
X463000Y122500D01*
Y124648D01*
G02X463200Y124848I200J0D01*
G37*
G36*
G01X754813Y14500D02*
X752500Y16813D01*
Y39000D01*
X735000Y56500D01*
Y93500D01*
X730500Y98000D01*
X726806D01*
X726805Y98002D01*
X726500D01*
X710500Y114001D01*
Y137777D01*
X710633Y137824D01*
G03X711302Y141598I-733J2076D01*
G02X711241Y142151I255J308D01*
G03X710500Y145462I-1741J1349D01*
G01Y151000D01*
X713385Y153885D01*
X713428Y153900D01*
G03X714778Y155250I-728J2078D01*
G01X714793Y155293D01*
X720000Y160500D01*
X728232D01*
G03X730768I1268J1800D01*
G01X732132D01*
G03X734881Y160670I1268J1800D01*
G02X735419I269J-296D01*
G03X737957Y164232I1480J1630D01*
G02X737866Y164866I192J351D01*
G01X755000Y182000D01*
Y229000D01*
X770500Y244500D01*
Y250342D01*
G03Y255058I-1100J2358D01*
G01Y266000D01*
X774000Y269500D01*
X803500D01*
X809399Y263601D01*
X809398Y263518D01*
G03X812018Y260898I2602J-18D01*
G01X812101Y260899D01*
X816500Y256500D01*
Y75000D01*
X814500Y73000D01*
X793000D01*
X789500Y69500D01*
Y26000D01*
X778000Y14500D01*
X772631D01*
G03X768369I-2131J-1493D01*
G01X754813D01*
G37*
%LPC*%
G75*
G36*
G01X15440Y107333D02*
G03Y106667I222J-333D01*
G02X12560I-1440J-2167D01*
G03Y107333I-222J333D01*
G02X15440I1440J2167D01*
G37*
G36*
G01X25900Y79742D02*
G02X22714Y78542I-899J-2442D01*
G03X22500Y79108I-352J191D01*
G02X25794Y82570I900J2442D01*
G03X26506Y82523I368J157D01*
G02X26442Y80393I1894J-1123D01*
G03X25728Y80388I-356J-183D01*
G02X25686Y80308I-2324J1169D01*
G03X25900Y79742I352J-191D01*
G37*
G36*
G01X9112Y264493D02*
Y260628D01*
X9102Y260544D01*
G02X6088Y260713I-1502J169D01*
G01Y264483D01*
G02X9112Y264493I1512J0D01*
G37*
G36*
G01X15102Y258531D02*
Y254666D01*
X15092Y254582D01*
G02X12078Y254751I-1502J169D01*
G01Y258521D01*
G02X15102Y258531I1512J0D01*
G37*
G36*
G01X9112Y252682D02*
Y248817D01*
X9102Y248733D01*
G02X6088Y248902I-1502J169D01*
G01Y252673D01*
G02X9112Y252682I1512J-1D01*
G37*
G36*
G01X15102Y246720D02*
Y242855D01*
X15092Y242771D01*
G02X12078Y242940I-1502J169D01*
G01Y246710D01*
G02X15102Y246720I1512J0D01*
G37*
G36*
G01X9112Y240871D02*
Y237006D01*
X9102Y236922D01*
G02X6088Y237091I-1502J169D01*
G01Y240861D01*
G02X9112Y240871I1512J0D01*
G37*
G36*
G01X14602Y234909D02*
Y231044D01*
X14592Y230960D01*
G02X11578Y231129I-1502J169D01*
G01Y234900D01*
G02X14602Y234909I1512J-1D01*
G37*
G36*
G01X36302Y212161D02*
Y208336D01*
G02X33298I-1502J-36D01*
G01Y212164D01*
G02X36302I1502J36D01*
G01Y212161D01*
G37*
G36*
G01X8950Y165423D02*
G03X9550I300J264D01*
G02X13119Y161663I1950J-1723D01*
G03Y161037I249J-313D01*
G02X9550Y157277I-1619J-2037D01*
G03X8950I-300J-264D01*
G02X5381Y161037I-1950J1723D01*
G03Y161663I-249J313D01*
G02X8950Y165423I1619J2037D01*
G37*
G36*
G01X54153Y132402D02*
G03X54685Y132387I274J291D01*
G02X54590Y129098I1415J-1687D01*
G03X54058Y129113I-274J-291D01*
G02X54153Y132402I-1415J1687D01*
G37*
G36*
G01X105770Y109093D02*
G03Y108507I273J-293D01*
G02X102230I-1770J-1907D01*
G03Y109093I-273J293D01*
G02X102277Y112950I1770J1907D01*
G03Y113550I-264J300D01*
G02X105723I1723J1950D01*
G03Y112950I264J-300D01*
G02X105770Y109093I-1723J-1950D01*
G37*
G36*
G01X69756Y93342D02*
G03Y93058I141J-142D01*
G02X66644I-1556J-1558D01*
G03Y93342I-141J142D01*
G02X69756I1556J1558D01*
G37*
G36*
G01X91891Y86610D02*
G03X92153Y86103I380J-125D01*
G02X89409Y84690I-653J-2103D01*
G03X89147Y85197I-380J125D01*
G02X88341Y88949I653J2103D01*
G03X88372Y89518I-265J300D01*
G02X91459Y89351I1628J1482D01*
G03X91428Y88782I265J-300D01*
G02X91891Y86610I-1628J-1482D01*
G37*
G36*
G01X96342Y74644D02*
G03X96058I-142J-141D01*
G02Y77756I-1558J1556D01*
G03X96342I142J141D01*
G02Y74644I1558J-1556D01*
G37*
G36*
G01X94006Y60889D02*
G03X93823Y61105I-199J17D01*
G02X92487Y61700I177J2195D01*
G03X92204Y61692I-138J-145D01*
G02X92113Y64800I-1604J1508D01*
G03X92396Y64808I138J145D01*
G02X96194Y63111I1604J-1508D01*
G03X96377Y62895I199J-17D01*
G02X94006Y60889I-177J-2195D01*
G37*
G36*
G01X103450Y52888D02*
X100050D01*
G02Y55912I0J1512D01*
G01X103451D01*
G02X104962Y54410I-1J-1512D01*
G01Y54315D01*
X104952Y54231D01*
G02X103450Y52888I-1502J168D01*
G37*
G36*
G01X88700D02*
X85299D01*
G02X85300Y55912I1J1512D01*
G01X88700D01*
G02X90212Y54410I0J-1512D01*
G01Y54315D01*
X90202Y54231D01*
G02X88700Y52888I-1502J168D01*
G37*
G36*
G01X45845Y271808D02*
G02X44095Y273582I-3128J-1336D01*
G03X44648Y274032I162J365D01*
G02X46303Y272355I2152J468D01*
G03X45845Y271808I-90J-390D01*
G37*
G36*
G01X31585Y142338D02*
G02X28174Y142787I-1885J-1138D01*
G03X28203Y143332I-278J288D01*
G02X28341Y146820I1997J1668D01*
G03Y147380I-286J280D01*
G02Y151020I1859J1820D01*
G03Y151580I-286J280D01*
G02X28385Y155264I1859J1820D01*
G03X28398Y155824I-279J287D01*
G02X31063Y160088I1902J1776D01*
G03X31556Y160607I117J382D01*
G02X33237Y159012I2444J893D01*
G03X32744Y158493I-117J-382D01*
G02X32115Y155736I-2444J-893D01*
G03X32102Y155176I279J-287D01*
G02X32059Y151580I-1902J-1776D01*
G03Y151020I286J-280D01*
G02Y147380I-1859J-1820D01*
G03Y146820I286J-280D01*
G02X31697Y142872I-1859J-1820D01*
G03X31585Y142338I230J-327D01*
G37*
G36*
G01X82342Y267944D02*
G03X82058I-142J-141D01*
G02Y271056I-1558J1556D01*
G03X82342I142J141D01*
G02Y267944I1558J-1556D01*
G37*
G36*
G01X101979Y265710D02*
G03X102072Y265111I304J-259D01*
G02X98721Y264590I-1372J-2211D01*
G03X98628Y265189I-304J259D01*
G02X101979Y265710I1372J2211D01*
G37*
G36*
G01X220169Y253057D02*
G03X219596Y252724I-174J-360D01*
G02X215717Y255164I-2596J176D01*
G03X215744Y255843I-197J348D01*
G02X219797Y258166I1456J2157D01*
G03X220343Y257820I399J26D01*
G02X220169Y253057I957J-2420D01*
G37*
G36*
G01X71410Y246899D02*
G03X71677Y246799I183J81D01*
G02X73008Y246964I924J-1999D01*
G03X73469Y247256I74J393D01*
G02X77067Y248342I2131J-556D01*
G03X77350Y248359I133J149D01*
G02X80695Y248306I1650J-1459D01*
G03X80978Y248281I154J128D01*
G02X80705Y245194I1422J-1681D01*
G03X80422Y245219I-154J-128D01*
G02X77533Y245258I-1422J1681D01*
G03X77250Y245241I-133J-149D01*
G02X75192Y244536I-1650J1459D01*
G03X74731Y244244I-74J-393D01*
G02X70590Y243901I-2131J556D01*
G03X70323Y244001I-183J-81D01*
G02X71410Y246899I-923J1999D01*
G37*
G36*
G01X114057Y223592D02*
G03X114041Y222946I228J-329D01*
G02X111443Y223008I-1341J-1746D01*
G03X111459Y223654I-228J329D01*
G02X114057Y223592I1341J1746D01*
G37*
G36*
G01X311569Y267005D02*
G03X311201Y266620I32J-399D01*
G02X308831Y268895I-2201J80D01*
G03X309199Y269280I-32J399D01*
G02X311569Y267005I2201J-80D01*
G37*
G36*
G01X352155Y113078D02*
G03X352077Y112517I241J-319D01*
G02X350187Y112780I-1077J-817D01*
G03X350265Y113341I-241J319D01*
G02X352155Y113078I1077J817D01*
G37*
G36*
G01X384277Y169528D02*
G02X382348Y167767I-729J-1138D01*
G03X381652Y167792I-355J-184D01*
G02X381700Y169123I-1152J708D01*
G03X382396Y169098I355J184D01*
G02X382931Y169593I1152J-708D01*
G03X382964Y170286I-183J356D01*
G02X384310Y170221I730J1138D01*
G03X384277Y169528I183J-356D01*
G37*
G36*
G01X378618Y164480D02*
G02Y166000I-1118J760D01*
G03X379280I331J225D01*
G02Y164480I1118J-760D01*
G03X378618I-331J-225D01*
G37*
G36*
G01X385599Y162818D02*
G02X385580Y161526I1178J-663D01*
G03X384878Y161536I-354J-187D01*
G02X383057Y163388I-1178J663D01*
G03X383076Y164082I-190J352D01*
G02X384931Y165946I705J1153D01*
G03X385620Y165961I340J210D01*
G02X385650Y164589I1180J-661D01*
G03X384961Y164574I-340J-210D01*
G02X384424Y164046I-1179J662D01*
G03X384405Y163352I190J-352D01*
G02X384897Y162828I-704J-1154D01*
G03X385599Y162818I354J187D01*
G37*
G36*
G01X368703Y160323D02*
G02X367313Y160392I-752J-1123D01*
G03X367347Y161077I-189J353D01*
G02X367470Y163396I753J1123D01*
G03Y164104I-187J354D01*
G02X368730I630J1196D01*
G03Y163396I187J-354D01*
G02X369254Y162905I-629J-1197D01*
G03X369952Y162932I341J208D01*
G02X370003Y161615I1205J-613D01*
G03X369305Y161588I-341J-208D01*
G02X368737Y161008I-1205J612D01*
G03X368703Y160323I189J-353D01*
G37*
G36*
G01X372357Y158282D02*
G02X372251Y159760I-1181J658D01*
G03X372919Y159808I318J242D01*
G02X373025Y158330I1181J-658D01*
G03X372357Y158282I-318J-242D01*
G37*
G36*
G01X381145Y147695D02*
G02X379747Y147753I-747J-1127D01*
G03X379775Y148437I-193J350D01*
G02X379320Y148946I748J1126D01*
G03X378624Y148974I-356J-183D01*
G02X378678Y150306I-1148J714D01*
G03X379374Y150278I356J183D01*
G02X381692Y150242I1148J-714D01*
G03X382389Y150251I346J201D01*
G02X384240Y148426I1186J-648D01*
G03X384234Y147733I197J-348D01*
G02X382883Y147745I-686J-1165D01*
G03X382889Y148438I-197J348D01*
G02X382405Y148925I686J1165D01*
G03X381708Y148916I-346J-201D01*
G02X381173Y148379I-1187J647D01*
G03X381145Y147695I193J-350D01*
G37*
G36*
G01X362346Y147737D02*
G02X360900Y147639I-646J-1188D01*
G03X360854Y148312I-237J322D01*
G02X362300Y148410I646J1188D01*
G03X362346Y147737I237J-322D01*
G37*
G36*
G01X368659Y144613D02*
G02X367373Y144602I-633J-1195D01*
G03X367367Y145305I-194J350D01*
G02X368653Y145316I633J1195D01*
G03X368659Y144613I194J-350D01*
G37*
G36*
G01X382265Y144048D02*
G02X382212Y142651I1130J-742D01*
G03X381528Y142676I-350J-194D01*
G02X381581Y144073I-1130J742D01*
G03X382265Y144048I350J194D01*
G37*
G36*
G01X388062Y142444D02*
G02X388037Y144147I-1062J836D01*
G03X388659Y144156I307J256D01*
G02X388684Y142453I1062J-836D01*
G03X388062Y142444I-307J-256D01*
G37*
G36*
G01X362394Y141444D02*
G02X361038Y141432I-668J-1176D01*
G03X361032Y142124I-203J344D01*
G02X362820Y144057I668J1176D01*
G03X363487Y144064I331J224D01*
G02X365372Y142203I1134J-737D01*
G03X365432Y141505I222J-333D01*
G02X364135Y141393I-547J-1237D01*
G03X364075Y142091I-222J333D01*
G02X363501Y142571I546J1237D01*
G03X362834Y142564I-331J-224D01*
G02X362388Y142136I-1134J736D01*
G03X362394Y141444I203J-344D01*
G37*
G36*
G01X372366Y136249D02*
G02X372319Y137612I-1190J641D01*
G03X373010Y137635I339J213D01*
G02X373057Y136272I1190J-641D01*
G03X372366Y136249I-339J-213D01*
G37*
G36*
G01X365317Y135203D02*
G02X364006Y135160I-617J-1203D01*
G03X363983Y135860I-205J344D01*
G02X365294Y135903I617J1203D01*
G03X365317Y135203I205J-344D01*
G37*
G36*
G01X381067Y135104D02*
G02X379791Y135135I-667J-1176D01*
G03X379808Y135840I-180J357D01*
G02X381652Y137682I667J1176D01*
G03X382358Y137700I348J197D01*
G02X382390Y136430I1209J-605D01*
G03X381684Y136412I-348J-197D01*
G02X381084Y135809I-1210J604D01*
G03X381067Y135104I180J-357D01*
G37*
G36*
G01X378374Y122240D02*
G02X377119Y122276I-662J-1179D01*
G03X377139Y122984I-176J359D01*
G02X378394Y122948I662J1179D01*
G03X378374Y122240I176J-359D01*
G37*
G36*
G01X370781Y114808D02*
G02X369215Y114809I-784J-1102D01*
G03X369216Y115461I-231J326D01*
G02X369341Y117744I784J1102D01*
G03X369364Y118429I-194J349D01*
G02Y120697I736J1134D01*
G03X369341Y121382I-217J336D01*
G02X368978Y121678I660J1180D01*
G03X368366Y121670I-303J-261D01*
G02X366525Y123621I-1045J858D01*
G03X366502Y124283I-236J323D01*
G02X368314Y126224I719J1145D01*
G03X368976Y126247I323J236D01*
G02X371131Y126427I1145J-719D01*
G03X371747Y126450I299J266D01*
G02X371811Y124729I1074J-822D01*
G03X371195Y124706I-299J-266D01*
G02X370793Y124355I-1073J823D01*
G03X370765Y123678I198J-347D01*
G02X370736Y121429I-765J-1115D01*
G03X370759Y120744I217J-336D01*
G02X371068Y120506I-662J-1179D01*
G03X371662Y120529I287J279D01*
G02X371732Y118720I1038J-866D01*
G03X371138Y118697I-287J-279D01*
G02X370759Y118382I-1039J865D01*
G03X370736Y117697I194J-349D01*
G02X370782Y115460I-736J-1134D01*
G03X370781Y114808I231J-326D01*
G37*
G36*
G01X378539Y113195D02*
G02X377074Y113204I-739J-1132D01*
G03X377079Y113876I-214J338D01*
G02X378544Y113867I739J1132D01*
G03X378539Y113195I214J-338D01*
G37*
G36*
G01X688597Y186283D02*
G03X688714Y185751I345J-203D01*
G02X685559Y185061I-1258J-1807D01*
G03X685442Y185593I-345J203D01*
G02X688597Y186283I1258J1807D01*
G37*
G36*
G01X691020Y177409D02*
G03X691032Y177126I147J-136D01*
G02X687927Y176991I-1485J-1626D01*
G03X687915Y177274I-147J136D01*
G02X691020Y177409I1485J1626D01*
G37*
G36*
G01X638693Y153587D02*
G03X638410Y153562I-129J-153D01*
G02X635144Y153433I-1691J1410D01*
G03X634861Y153436I-143J-140D01*
G02X634894Y156547I-1542J1572D01*
G03X635177Y156544I143J140D01*
G02X638136Y156657I1542J-1572D01*
G03X638419Y156682I129J153D01*
G02X641788Y156698I1691J-1410D01*
G03X642071Y156675I153J129D01*
G02X641822Y153574I1429J-1675D01*
G03X641539Y153597I-153J-129D01*
G02X638693Y153587I-1429J1675D01*
G37*
G36*
G01X658402Y144000D02*
Y124088D01*
X655157Y120843D01*
G02X652043Y123957I-1557J1557D01*
G01X653998Y125912D01*
Y144000D01*
G02X654934Y145801I2201J0D01*
G03X654977Y146421I-230J327D01*
G02X654999Y149666I1500J1612D01*
G03X655013Y149948I-134J148D01*
G02X658120Y149797I1629J1482D01*
G03X658106Y149515I134J-148D01*
G02X657743Y146231I-1629J-1482D01*
G03X657700Y145611I230J-327D01*
G02X658402Y144000I-1500J-1612D01*
G37*
G36*
G01X700645Y116719D02*
G03X700667Y116437I152J-130D01*
G02X697566Y116189I-1426J-1678D01*
G03X697544Y116471I-152J130D01*
G02X700645Y116719I1426J1678D01*
G37*
G36*
G01X637154Y110045D02*
G03X637616Y109568I391J-83D01*
G02X635846Y107855I384J-2168D01*
G03X635384Y108332I-391J83D01*
G02X637154Y110045I-384J2168D01*
G37*
G36*
G01X413104Y146184D02*
G02X413011Y147570I-1204J615D01*
G03X413696Y147616I329J228D01*
G02X416081Y147659I1204J-616D01*
G03X416766Y147636I349J194D01*
G02X419037Y147632I1134J-736D01*
G03X419713Y147637I336J216D01*
G02X420030Y147989I1148J-715D01*
G03Y148621I-246J316D01*
G02X421692I831J1066D01*
G03Y147989I246J-316D01*
G02X419724Y146191I-831J-1066D01*
G03X419048Y146186I-336J-216D01*
G02X416719Y146241I-1148J714D01*
G03X416034Y146264I-349J-194D01*
G02X413789Y146230I-1134J736D01*
G03X413104Y146184I-329J-228D01*
G37*
G36*
G01X422126Y130672D02*
G02X422040Y132112I-1184J652D01*
G03X422716Y132152I325J233D01*
G02X422802Y130712I1184J-652D01*
G03X422126Y130672I-325J-233D01*
G37*
G36*
G01X590696Y126157D02*
X590447Y125908D01*
X590521Y125776D01*
G02X589784Y126557I-1922J-1075D01*
G03X590398Y126894I214J337D01*
G01Y143734D01*
G02X593681Y146630I1801J1267D01*
G03X594226Y146636I269J296D01*
G02X594608Y143155I1518J-1595D01*
G03X594002Y142812I-206J-343D01*
G01Y128123D01*
X594135Y128076D01*
G02X591242Y125563I-735J-2076D01*
G01X591230Y125623D01*
X590696Y126157D01*
G37*
G36*
G01X811059Y211880D02*
G03Y211320I286J-280D01*
G02X807341I-1859J-1820D01*
G03Y211880I-286J280D01*
G02X807581Y215737I1859J1820D01*
G03Y216363I-249J313D01*
G02X810819I1619J2037D01*
G03Y215737I249J-313D01*
G02X811059Y211880I-1619J-2037D01*
G37*
G36*
G01X812359Y194680D02*
G03Y194120I286J-280D01*
G02X808641I-1859J-1820D01*
G03Y194680I-286J280D01*
G02X812359I1859J1820D01*
G37*
G36*
G01X765557Y190725D02*
G03Y190085I240J-320D01*
G02X762443I-1557J-2085D01*
G03Y190725I-240J320D01*
G02X762375Y194843I1557J2085D01*
G03Y195467I-249J312D01*
G02X762443Y199585I1625J2033D01*
G03Y200225I-240J320D01*
G02X765557I1557J2085D01*
G03Y199585I240J-320D01*
G02X765625Y195467I-1557J-2085D01*
G03Y194843I249J-312D01*
G02X765557Y190725I-1625J-2033D01*
G37*
G36*
G01X749019Y160370D02*
G03X748481I-269J-296D01*
G02Y163630I-1481J1630D01*
G03X749019I269J296D01*
G02Y160370I1481J-1630D01*
G37*
G36*
G01X811273Y158919D02*
G03X811258Y158386I291J-275D01*
G02X807827Y158481I-1758J-1486D01*
G03X807842Y159014I-291J275D01*
G02X808007Y162162I1758J1486D01*
G03X808022Y162724I-277J289D01*
G02X811293Y162638I1678J1576D01*
G03X811278Y162076I277J-289D01*
G02X811273Y158919I-1678J-1576D01*
G37*
G36*
G01X719756Y148842D02*
G03Y148558I141J-142D01*
G02X716644I-1556J-1558D01*
G03Y148842I-141J142D01*
G02X719756I1556J1558D01*
G37*
G36*
G01X786822Y142651D02*
G03X786208I-307J-255D01*
G02Y145469I-1693J1409D01*
G03X786822I307J255D01*
G02X790208I1693J-1409D01*
G03X790822I307J255D01*
G02X791106Y145753I1693J-1409D01*
G03Y146367I-255J307D01*
G02X794208Y149469I1409J1693D01*
G03X794822I307J255D01*
G02X798208I1693J-1409D01*
G03X798822I307J255D01*
G02X801924Y146367I1693J-1409D01*
G03Y145753I255J-307D01*
G02X798822Y142651I-1409J-1693D01*
G03X798208I-307J-255D01*
G02X794822I-1693J1409D01*
G03X794208I-307J-255D01*
G02X790822I-1693J1409D01*
G03X790208I-307J-255D01*
G02X786822I-1693J1409D01*
G37*
G36*
G01X812548Y132296D02*
G03Y131704I269J-296D01*
G02X809452I-1548J-1704D01*
G03Y132296I-269J296D01*
G02Y135704I1548J1704D01*
G03Y136296I-269J296D01*
G02X809373Y139629I1548J1704D01*
G03X809403Y140162I-282J283D01*
G02X812827Y139971I1798J1438D01*
G03X812797Y139438I282J-283D01*
G02X812548Y136296I-1797J-1438D01*
G03Y135704I269J-296D01*
G02Y132296I-1548J-1704D01*
G37*
G36*
G01X746513Y132070D02*
G03Y131456I255J-307D01*
G02X743695I-1409J-1693D01*
G03Y132070I-255J307D01*
G02X743411Y132354I1409J1693D01*
G03X742797I-307J-255D01*
G02Y135172I-1693J1409D01*
G03X743411I307J255D01*
G02X743695Y135456I1693J-1409D01*
G03Y136070I-255J307D01*
G02X746513I1409J1693D01*
G03Y135456I255J-307D01*
G02X746797Y135172I-1409J-1693D01*
G03X747411I307J255D01*
G02Y132354I1693J-1409D01*
G03X746797I-307J-255D01*
G02X746513Y132070I-1693J1409D01*
G37*
G36*
G01X729434Y130840D02*
G03X729211Y130212I97J-388D01*
G02X726914Y131029I-1763J-1319D01*
G03X727137Y131657I-97J388D01*
G02X726989Y134071I1763J1320D01*
G03X726820Y134628I-347J199D01*
G02X725920Y137746I980J1972D01*
G03X725826Y138269I-341J209D01*
G02X729067Y138854I1361J1731D01*
G03X729161Y138331I341J-209D01*
G02X729711Y135505I-1361J-1731D01*
G03X729880Y134948I347J-199D01*
G02X729434Y130840I-980J-1972D01*
G37*
G36*
G01X732000Y120498D02*
G03X731600Y120114I0J-400D01*
G02X729400Y122402I-2200J86D01*
G03X729800Y122786I0J400D01*
G02X732000Y120498I2200J-86D01*
G37*
G36*
G01X749512Y107498D02*
X726998D01*
X725500Y106000D01*
X724000D01*
X723757Y106243D01*
X723702Y106256D01*
G02X722643Y109957I498J2144D01*
G01X724588Y111902D01*
X724901D01*
X725000Y112000D01*
X747787D01*
X748726Y112940D01*
G03X748498Y113619I-283J283D01*
G02X748720Y118001I302J2181D01*
G03X749105Y118369I-14J400D01*
G02X751554Y120387I2195J-169D01*
G03X752000Y120785I46J397D01*
G01Y136000D01*
X752298Y136298D01*
Y136412D01*
X757488Y141602D01*
X757602D01*
X759000Y143000D01*
X773398D01*
Y179563D01*
X777937Y184102D01*
X785549D01*
G02X785762Y184512I2050J-805D01*
G01X785852Y184648D01*
X782500Y188000D01*
Y204000D01*
X786000Y207500D01*
Y220000D01*
X788000Y222000D01*
X791000D01*
X792500Y220500D01*
Y208500D01*
X793000Y208000D01*
X795000D01*
X796500Y206500D01*
Y203000D01*
X796000Y202500D01*
Y195000D01*
X801500Y189500D01*
Y186000D01*
X800000Y184500D01*
X790076D01*
G03X789695Y183977I0J-400D01*
G02X789242Y181833I-2095J-677D01*
G03X789259Y181550I149J-133D01*
G02X786289Y178298I-1459J-1650D01*
G01X779492D01*
X778602Y177408D01*
Y144602D01*
G03X779001Y144202I400J0D01*
G02X779000Y139798I-1J-2202D01*
G01Y122500D01*
X770695Y114195D01*
X770699Y114107D01*
G02X768393Y111801I-2199J-107D01*
G01X768305Y111805D01*
X767418Y110918D01*
X767405Y110895D01*
G02X766605Y110095I-1905J1105D01*
G01X766582Y110082D01*
X765102Y108602D01*
Y104490D01*
X764506Y103895D01*
X764502Y103819D01*
G02X760617Y102542I-2198J138D01*
G03X760335Y102566I-153J-129D01*
G02X756779Y103719I-1419J1684D01*
G03X756536Y103864I-194J-49D01*
G02X754004Y106931I-536J2136D01*
G03X753642Y107500I-362J169D01*
G01X749513D01*
X749512Y107498D01*
G37*
G36*
G01X776680Y100641D02*
G03X776120I-280J-286D01*
G02X772577Y104450I-1820J1859D01*
G03Y105050I-264J300D01*
G02X776120Y108859I1723J1950D01*
G03X776680I280J286D01*
G02X780223Y105050I1820J-1859D01*
G03Y104450I264J-300D01*
G02X776680Y100641I-1723J-1950D01*
G37*
G36*
G01X801059Y100980D02*
G03Y100420I286J-280D01*
G02X797341I-1859J-1820D01*
G03Y100980I-286J280D01*
G02X797301Y104579I1859J1820D01*
G03X797275Y105152I-291J274D01*
G02X797437Y109180I1725J1948D01*
G03Y109820I-240J320D01*
G02X797141Y113720I1563J2080D01*
G03Y114280I-286J280D01*
G02X800725Y118048I1859J1820D01*
G03X801325Y118128I265J299D01*
G02X805359Y114880I2175J-1427D01*
G03Y114320I286J-280D01*
G02X801775Y110552I-1859J-1820D01*
G03X801175Y110472I-265J-299D01*
G02X800563Y109820I-2175J1428D01*
G03Y109180I240J-320D01*
G02X801254Y108401I-1562J-2081D01*
G03X801800Y108254I346J199D01*
G02X802305Y103523I1300J-2254D01*
G03X801785Y103096I-122J-381D01*
G02X801059Y100980I-2585J-296D01*
G37*
G36*
G01X785550Y91277D02*
G03X784950I-300J-264D01*
G02Y94723I-1950J1723D01*
G03X785550I300J264D01*
G02Y91277I1950J-1723D01*
G37*
G36*
G01X794550Y81277D02*
G03X793950I-300J-264D01*
G02X790381Y85037I-1950J1723D01*
G03Y85663I-249J313D01*
G02X793950Y89423I1619J2037D01*
G03X794550I300J264D01*
G02X798119Y85663I1950J-1723D01*
G03Y85037I249J-313D01*
G02X794550Y81277I-1619J-2037D01*
G37*
G36*
G01X776519Y29677D02*
G03X775981I-269J-296D01*
G02Y32937I-1481J1630D01*
G03X776519I269J296D01*
G02Y29677I1481J-1630D01*
G37*
G36*
G01X810959Y226220D02*
G02X807241I-1859J-1820D01*
G03Y226780I-286J280D01*
G02X807900Y230909I1859J1820D01*
G03X807847Y231642I-184J355D01*
G02X806841Y235920I853J2458D01*
G03Y236480I-286J280D01*
G02X807028Y240294I1859J1820D01*
G03Y240906I-257J306D01*
G02X806841Y244720I1672J1994D01*
G03Y245280I-286J280D01*
G02X807339Y249317I1859J1820D01*
G03X807445Y249904I-210J341D01*
G02X808457Y253884I2055J1596D01*
G03Y254616I-161J366D01*
G02X810543I1043J2384D01*
G03Y253884I161J-366D01*
G02X810861Y249283I-1043J-2384D01*
G03X810755Y248696I210J-341D01*
G02X810559Y245280I-2055J-1596D01*
G03Y244720I286J-280D01*
G02X810372Y240906I-1859J-1820D01*
G03Y240294I257J-306D01*
G02X810559Y236480I-1672J-1994D01*
G03Y235920I286J-280D01*
G02X809900Y231791I-1859J-1820D01*
G03X809953Y231058I184J-355D01*
G02X810959Y226780I-853J-2458D01*
G03Y226220I286J-280D01*
G37*
G36*
G01X741621Y115492D02*
G02X737354Y115394I-2121J-592D01*
G03X736862Y115871I-390J90D01*
G02X738446Y117506I-562J2129D01*
G03X738938Y117029I390J-90D01*
G02X739579Y117101I564J-2129D01*
G03X739979Y117608I15J400D01*
G02X742021Y115999I2121J592D01*
G03X741621Y115492I-15J-400D01*
G37*
G36*
G01X784043Y115384D02*
G02X781957I-1043J-2384D01*
G03Y116116I-161J366D01*
G02X781277Y120450I1043J2384D01*
G03Y121050I-264J300D01*
G02X784723I1723J1950D01*
G03Y120450I264J-300D01*
G02X784043Y116116I-1723J-1950D01*
G03Y115384I161J-366D01*
G37*
G36*
G01X766828Y85962D02*
G02X765292Y87278I-2328J-1162D01*
G03X765772Y87838I122J381D01*
G02X767308Y86522I2328J1162D01*
G03X766828Y85962I-122J-381D01*
G37*
G54D32*
X538300Y15200D03*
G54D28*
X14400Y98000D03*
X129500Y252500D03*
X129000Y268000D03*
X166500Y241000D03*
X345089Y73089D03*
X721200Y65100D03*
X739500Y75500D03*
X759000Y37507D03*
X760400Y88700D03*
X761300Y95700D03*
X763600Y168000D03*
X769500Y234500D03*
X781500Y51000D03*
X777000Y93100D03*
G54D29*
X41200Y90300D03*
X62900Y79900D03*
X16844Y203100D03*
X16900Y269000D03*
X30000Y136000D03*
X57600Y136900D03*
X58000Y141750D03*
X50000Y270000D03*
X69235Y99735D03*
X90500Y101000D03*
X86100Y97700D03*
X86500Y113500D03*
X80500D03*
X85500Y135400D03*
X75300Y259900D03*
X82100Y259600D03*
X88900Y246700D03*
X110166Y239500D03*
X104900Y248800D03*
X97600Y246500D03*
X109500Y258300D03*
X112700Y231400D03*
X146000Y231000D03*
X146500Y236500D03*
X155300Y254000D03*
X144200Y270700D03*
X165700Y254000D03*
X195000Y234000D03*
X206000D03*
X202200Y89500D03*
X528400Y145041D03*
X608300Y144890D03*
X648500Y144000D03*
X650500Y155000D03*
X661000Y173800D03*
X673100Y179455D03*
X682600Y114300D03*
X714000Y118500D03*
X715700Y124200D03*
X714900Y131900D03*
X718825Y155453D03*
X738000Y65700D03*
X738500Y90000D03*
X736900Y98500D03*
X752500Y49007D03*
X749500Y101500D03*
X752191Y146613D03*
X793000Y174500D03*
X805500Y128000D03*
G54D30*
X344500Y94000D03*
X344523Y98477D03*
X347230Y100190D03*
X348076Y108910D03*
X355175Y108212D03*
X354333Y125665D03*
X358000Y115500D03*
X366400Y112200D03*
X365721Y115528D03*
X359942Y110924D03*
X358500Y137000D03*
X367121Y128628D03*
X362111Y130128D03*
X368026Y137118D03*
X367992Y133982D03*
X364700Y152713D03*
X368026Y140268D03*
X364600Y165300D03*
X368000Y168500D03*
X371100Y168700D03*
X386708Y137118D03*
X380443Y130102D03*
X374200Y149494D03*
Y143294D03*
X380400Y152700D03*
X374200Y140144D03*
X383500Y159000D03*
X380500Y162025D03*
X387000Y155850D03*
X377500Y156000D03*
X374300Y155800D03*
X389848Y137118D03*
X390205Y133858D03*
X393000Y140268D03*
X416000Y135983D03*
X418000Y142500D03*
X413300Y139100D03*
X408800Y147000D03*
X413400Y142700D03*
X431700Y128300D03*
X419500Y136400D03*
X430100Y131500D03*
X425000Y135350D03*
X422400Y139000D03*
X424856Y142270D03*
X427600Y143841D03*
X426900Y147100D03*
X428390Y139059D03*
X430694Y142275D03*
X431100Y145500D03*
X421500Y142400D03*
X443400Y148900D03*
X542100Y15107D03*
X536485Y22907D03*
X533200D03*
X542407Y30882D03*
X544860Y12407D03*
X550000Y12507D03*
X552800Y14807D03*
X554460Y22907D03*
X557745D03*
X553079Y30712D03*
X549500Y31607D03*
X545928Y31047D03*
X568555Y12407D03*
X561200Y12507D03*
X571600Y14207D03*
X564400Y14307D03*
X570852Y33204D03*
X561456Y30902D03*
X569800Y29807D03*
X565091Y30815D03*
X587940Y12417D03*
X582655Y12407D03*
X577824Y22907D03*
X579800Y14807D03*
X574539Y22907D03*
X581450Y30707D03*
X585179Y30867D03*
X594600Y6707D03*
X601704Y22907D03*
X589300Y33007D03*
X594400Y36207D03*
X610952Y12307D03*
X607300Y14507D03*
X671290Y12457D03*
X680580Y22807D03*
X677295D03*
X674320Y14219D03*
X674400Y31307D03*
X684760Y12256D03*
X690102Y12502D03*
X692200Y15357D03*
X695029Y22853D03*
X682013Y14848D03*
X689624Y30383D03*
X693300Y30607D03*
X681900Y30907D03*
X685700Y30807D03*
X709000Y12407D03*
X702000Y12607D03*
X698277Y22855D03*
X705031Y14515D03*
X708900Y30407D03*
X704430Y33313D03*
X701800Y30807D03*
X723586Y14080D03*
X712182Y14124D03*
X718375Y22907D03*
X715090D03*
X720100Y14707D03*
X727000Y30407D03*
X712400Y30807D03*
X721747Y32954D03*
X723500Y29907D03*
X742200Y12407D03*
X728010Y12857D03*
X739000Y14407D03*
X731169Y14584D03*
X736091Y23607D03*
X732806D03*
X742100Y33007D03*
X740200Y29907D03*
X730500D03*
G54D31*
X502500Y6200D03*
X699000Y162255D03*
X784000Y31000D03*
X782000Y137000D03*
X809000Y149200D03*
G54D33*
X761417Y22798D03*
G54D26*
X11500Y68500D03*
X12000Y279000D03*
G54D27*
X45669Y77185D03*
%LPD*%
G75*
G36*
G01X788500Y220500D02*
X790500D01*
X791000Y220000D01*
Y208000D01*
X792500Y206500D01*
X794000D01*
X795000Y205500D01*
Y204000D01*
X794500Y203500D01*
Y194000D01*
X800000Y188500D01*
Y187000D01*
X799000Y186000D01*
X786500D01*
X784000Y188500D01*
Y203500D01*
X787500Y207000D01*
Y219500D01*
X788500Y220500D01*
G37*
G54D10*
X15400Y118000D03*
X10900D03*
X13000Y137000D03*
X15500Y122800D03*
X15000Y127500D03*
X11000Y122800D03*
X10500Y127500D03*
X13000Y141500D03*
X13100Y150600D03*
X13000Y146000D03*
X14500Y198000D03*
X4500Y228900D03*
X4600Y223100D03*
X4500Y234800D03*
X4400Y245100D03*
Y256700D03*
X5000Y275000D03*
X12600Y266900D03*
X15300Y285800D03*
X4900Y285700D03*
X25200Y286000D03*
X45500Y118000D03*
X37500Y264000D03*
X63500Y43500D03*
Y57500D03*
Y48000D03*
Y52500D03*
X50500Y160000D03*
X68500Y47500D03*
X73500Y48000D03*
X68000Y52500D03*
X95500Y93500D03*
X94000Y137500D03*
Y133000D03*
X99500Y91500D03*
Y96000D03*
X104000Y92000D03*
Y96500D03*
X105775Y137349D03*
X103175Y134050D03*
X98500Y137500D03*
X109000Y134050D03*
X98500Y133000D03*
X117500Y146950D03*
X116500Y211200D03*
X122250Y228750D03*
Y233000D03*
Y237300D03*
Y241500D03*
X134100Y96600D03*
X136500Y272500D03*
X189000Y87700D03*
X203100Y252900D03*
X216261Y74846D03*
X212600Y161500D03*
X211900Y253000D03*
X207500D03*
X233500Y258958D03*
X228000Y259000D03*
X236400Y95100D03*
X240565Y113365D03*
X248000Y259000D03*
X238500D03*
X243000D03*
X258400Y65600D03*
X252500Y259000D03*
X278200Y281350D03*
X282686Y281336D03*
X335700Y278751D03*
X331500D03*
X353500Y71900D03*
X357000Y69500D03*
X349300Y83000D03*
X345100D03*
X354200Y76400D03*
X359800Y72700D03*
X362700Y69600D03*
X474000Y9000D03*
X467200Y4400D03*
X481500Y8900D03*
X489600Y8800D03*
X497100D03*
X653000Y93000D03*
X650726Y125724D03*
X664212Y147993D03*
X678400Y114500D03*
X668411Y148089D03*
X678500Y141500D03*
X667061Y175239D03*
X693500Y148000D03*
X690000Y159000D03*
X694500D03*
X700089Y91411D03*
X701600Y104900D03*
X701400Y98400D03*
X710200Y201700D03*
X725632Y49600D03*
X721950Y51950D03*
X722000Y74500D03*
X717000D03*
X715000Y80300D03*
X714500Y85500D03*
X753500Y24007D03*
Y20007D03*
Y28507D03*
X755500Y16000D03*
X767500Y24007D03*
X760500Y29000D03*
X761000Y16007D03*
X767500Y28507D03*
Y19507D03*
X764200Y44200D03*
X767500Y33207D03*
X764500Y54000D03*
X764300Y49200D03*
X769500Y50000D03*
X761000Y58500D03*
X785830Y188700D03*
X785400Y202800D03*
X789000Y204979D03*
X789200Y214200D03*
Y209800D03*
X784500Y222500D03*
X789000Y223500D03*
X789200Y218700D03*
X786000Y228000D03*
Y232400D03*
X786200Y236900D03*
X786300Y241500D03*
X785000Y245800D03*
Y250200D03*
Y254900D03*
X789910Y187679D03*
X794110D03*
X798310Y187779D03*
X793500Y204979D03*
Y223500D03*
X793200Y228400D03*
Y232600D03*
Y237200D03*
Y242400D03*
X793300Y247200D03*
X795300Y260800D03*
X795400Y251700D03*
X795300Y256500D03*
Y265000D03*
G54D20*
G01X364895Y190941D02*
X364873D01*
X362707Y193107D01*
Y195200D01*
X363507Y196000D01*
Y200361D01*
X361500Y202368D01*
Y217400D01*
X359750Y219150D01*
X356100D01*
X354450Y217500D01*
X346600D01*
X345950Y218150D01*
X342750D01*
X342500Y217900D01*
X342400D01*
G01X364947Y193141D02*
X364854Y193048D01*
X363898D01*
X363507Y193439D01*
Y194868D01*
X364307Y195668D01*
Y200693D01*
X362300Y202700D01*
Y204880D01*
X362690Y205270D01*
Y206470D01*
X362300Y206860D01*
Y208060D01*
X362690Y208450D01*
Y209650D01*
X362300Y210040D01*
Y217732D01*
X360082Y219950D01*
X355768D01*
X354118Y218300D01*
X346932D01*
X346282Y218950D01*
X342750D01*
X342500Y219200D01*
X342400D01*
G01X369200Y189100D02*
X368234Y190066D01*
X367309D01*
X366575Y190800D01*
Y194920D01*
X366105Y195390D01*
Y203537D01*
X366700Y204132D01*
Y209300D01*
X363600Y212400D01*
Y218000D01*
X360600Y221000D01*
X355300D01*
X354000Y219700D01*
X352950D01*
X352700Y219450D01*
X352600D01*
G01X369106Y191903D02*
X368069Y190866D01*
X367641D01*
X367375Y191132D01*
Y195252D01*
X366905Y195722D01*
Y203205D01*
X367500Y203800D01*
Y209632D01*
X364400Y212732D01*
Y218332D01*
X360932Y221800D01*
X354968D01*
X353668Y220500D01*
X352950D01*
X352700Y220750D01*
X352600D01*
G01X361227Y227500D02*
Y227450D01*
X361477Y227200D01*
Y223123D01*
X365500Y219100D01*
Y212800D01*
X372749Y205551D01*
Y195407D01*
X372472Y195130D01*
Y191878D01*
X374000Y190350D01*
G01X362527Y227500D02*
Y227450D01*
X362277Y227200D01*
Y223455D01*
X366300Y219432D01*
Y213132D01*
X373549Y205883D01*
Y204615D01*
X373939Y204225D01*
Y203025D01*
X373549Y202635D01*
Y201435D01*
X373939Y201045D01*
Y199845D01*
X373549Y199455D01*
Y198255D01*
X373939Y197865D01*
Y196665D01*
X373549Y196275D01*
Y195075D01*
X373272Y194798D01*
Y193753D01*
X373351Y193672D01*
X373398Y193626D01*
X373922Y193103D01*
G01X323200Y200300D02*
X323300D01*
X323550Y200550D01*
X324193D01*
X324668Y200075D01*
X327075D01*
X328400Y201400D01*
X333032D01*
X333932Y202300D01*
X340368D01*
X341268Y201400D01*
X354032D01*
X356832Y204200D01*
X358668D01*
X359200Y203668D01*
Y200268D01*
X360672Y198796D01*
Y196672D01*
X359807Y195807D01*
Y192150D01*
X361257Y190700D01*
G01X323200Y201600D02*
X323300D01*
X323550Y201350D01*
X324525D01*
X325000Y200875D01*
X326743D01*
X328068Y202200D01*
X332700D01*
X333600Y203100D01*
X340700D01*
X341600Y202200D01*
X353700D01*
X356500Y205000D01*
X359000D01*
X360000Y204000D01*
Y200600D01*
X361472Y199128D01*
Y196340D01*
X360607Y195475D01*
Y194174D01*
X361257Y193524D01*
G01X358382Y212427D02*
X357755Y211800D01*
X356500D01*
X355400Y210700D01*
Y207800D01*
X353500Y205900D01*
X338632D01*
X337632Y206900D01*
X327968D01*
X327343Y206275D01*
X326475D01*
X326225Y206525D01*
X326125D01*
G01X358498Y210220D02*
X357718Y211000D01*
X356832D01*
X356200Y210368D01*
Y207468D01*
X353832Y205100D01*
X351020D01*
X350630Y204710D01*
X349430D01*
X349040Y205100D01*
X347840D01*
X347450Y204710D01*
X346250D01*
X345860Y205100D01*
X344660D01*
X344270Y204710D01*
X343070D01*
X342680Y205100D01*
X341480D01*
X341090Y204710D01*
X339890D01*
X339500Y205100D01*
X338300D01*
X337300Y206100D01*
X335142D01*
X334752Y205710D01*
X333552D01*
X333162Y206100D01*
X331962D01*
X331572Y205710D01*
X330372D01*
X329982Y206100D01*
X328300D01*
X327675Y205475D01*
X326475D01*
X326225Y205225D01*
X326125D01*
G01X318627Y157670D02*
X318698Y157741D01*
X318699D01*
X318700Y157740D01*
X319050D01*
X322200Y160890D01*
Y162152D01*
X324232Y164184D01*
X326874D01*
X329953Y167263D01*
X335763D01*
X342392Y173892D01*
Y179689D01*
X343851Y181148D01*
Y185640D01*
X345631Y187420D01*
G01X319547Y156751D02*
X319618Y156822D01*
Y157176D01*
X323000Y160558D01*
Y161820D01*
X324564Y163384D01*
X327206D01*
X330285Y166463D01*
X336095D01*
X336944Y167312D01*
X337495D01*
X338344Y168160D01*
Y168712D01*
X343192Y173560D01*
Y174977D01*
X343582Y175367D01*
Y176567D01*
X343192Y176957D01*
Y179357D01*
X344651Y180816D01*
Y183651D01*
X345500Y184500D01*
G01X342188Y183361D02*
X341449Y184100D01*
X340632D01*
X339432Y182900D01*
X328600D01*
X326450Y185050D01*
X325003D01*
X324753Y184800D01*
X324350D01*
G01Y186100D02*
X324717D01*
X324967Y185850D01*
X326782D01*
X328932Y183700D01*
X339100D01*
X340300Y184900D01*
X341449D01*
X342188Y185639D01*
X342233D01*
G01X354271Y84317D02*
X352900Y85688D01*
Y99600D01*
X359335Y106035D01*
X362803D01*
G01X365316Y108130D02*
Y104116D01*
X358600Y97400D01*
X357200D01*
X356100Y96300D01*
Y86900D01*
X366699Y76301D01*
X368793D01*
X370094Y75000D01*
G01X357900Y99200D02*
X356500D01*
X354500Y97200D01*
Y86600D01*
X366629Y74471D01*
X367370D01*
G01X376163Y80800D02*
X369600D01*
X364800Y85600D01*
Y91200D01*
G01X357721Y91779D02*
Y86879D01*
X366800Y77800D01*
X370547D01*
G01X373632Y78522D02*
X373353Y78801D01*
X369349D01*
X369348Y78800D01*
X368354D01*
X362100Y85054D01*
Y89300D01*
X361200Y90200D01*
G01X374410Y79300D02*
X374110Y79600D01*
X373967Y79601D01*
X369017D01*
X369016Y79600D01*
X368686D01*
X362900Y85386D01*
Y95800D01*
X361200Y97500D01*
G01X380400Y78900D02*
X377500Y81800D01*
X371000D01*
X366800Y86000D01*
Y96324D01*
X364874Y98250D01*
G01X368600Y90700D02*
Y91700D01*
X370700Y93800D01*
G01X374988Y235288D02*
X370800Y231100D01*
Y220600D01*
X371500Y219900D01*
Y214900D01*
X372700Y213700D01*
G01X385288Y235988D02*
X379500Y230200D01*
Y219400D01*
X379700Y219200D01*
G01X387588Y236088D02*
X381100Y229600D01*
Y224100D01*
X382600Y222600D01*
G01X382988Y235888D02*
X378000Y230900D01*
Y215250D01*
X379750Y213500D01*
G01X377288Y235788D02*
X372500Y231000D01*
Y221900D01*
X372800Y221600D01*
G01X382750Y229000D02*
X387538Y233788D01*
X387788D01*
X389888Y235888D01*
Y236138D01*
G01X397350Y80650D02*
X392500Y85500D01*
Y98500D01*
X388000Y103000D01*
Y108200D01*
X388011Y108211D01*
Y109413D01*
X388000Y109424D01*
Y113200D01*
X392843Y118043D01*
X393331D01*
G01X401200Y80500D02*
X395600Y86100D01*
Y102100D01*
X392200Y105500D01*
Y113956D01*
X393351Y115107D01*
G01X398500Y125604D02*
X398596D01*
X400000Y124200D01*
Y121286D01*
X399100Y120386D01*
Y108200D01*
X402400Y104900D01*
X412800D01*
X416350Y101350D01*
Y98950D01*
X416500Y98800D01*
G01X396251Y117999D02*
X395601Y117349D01*
Y113515D01*
X395150Y113064D01*
Y108150D01*
X401100Y102200D01*
X408100D01*
X409100Y101200D01*
Y85200D01*
X410400Y83900D01*
G01X405500Y82700D02*
Y95700D01*
X394350Y106850D01*
Y113450D01*
X394801Y113901D01*
Y118801D01*
X395498Y119498D01*
X397080D01*
X398512Y120930D01*
Y122815D01*
G01X397650Y115500D02*
X398050Y115100D01*
Y107150D01*
X401600Y103600D01*
X408900D01*
X411100Y101400D01*
Y99500D01*
X412700Y97900D01*
Y89900D01*
X416900Y85700D01*
G01X401749Y112418D02*
X406767Y107400D01*
X414408D01*
X425458Y96350D01*
X429750D01*
G01X401159Y119636D02*
Y118959D01*
X399900Y117700D01*
Y111800D01*
X405500Y106200D01*
X414476D01*
X420000Y100676D01*
Y94799D01*
X421599Y93200D01*
X424300D01*
X425600Y91900D01*
G01X431700Y97600D02*
X430000Y99300D01*
X423640D01*
X413977Y108963D01*
X407897D01*
X401353Y115507D01*
Y116562D01*
G01X401500Y125600D02*
Y125500D01*
X403500Y123500D01*
Y121600D01*
X406800Y118300D01*
Y113837D01*
X409174Y111463D01*
X414873D01*
X424264Y102072D01*
X434845D01*
X435108Y101809D01*
G01X392599Y181686D02*
X394163D01*
G03X396370Y182600I0J3121D01*
G01X398248Y184478D01*
G03X398750Y185690I-1212J1212D01*
G01X398757Y185697D01*
Y186817D01*
X401000Y189060D01*
Y201600D01*
X412800Y213400D01*
X416500D01*
X416950Y213850D01*
G01X393800Y225800D02*
Y212453D01*
X391800Y210453D01*
Y197800D01*
X389500Y195500D01*
Y193600D01*
G01X391800Y226500D02*
Y224000D01*
X390100Y222300D01*
Y202221D01*
X390900Y201421D01*
Y200621D01*
X390500Y200221D01*
X389300D01*
X388900Y199821D01*
Y197400D01*
X387892Y196392D01*
Y192890D01*
X388782Y192000D01*
X390100D01*
X390980Y191120D01*
Y186181D01*
X392624Y184537D01*
G01X395600Y184100D02*
Y185200D01*
X394150Y186650D01*
Y195750D01*
X395000Y196600D01*
Y207300D01*
X402524Y214824D01*
Y225500D01*
G01X395600Y190300D02*
Y190400D01*
X395800Y190600D01*
Y192149D01*
X398200Y194549D01*
Y202650D01*
X406375Y210825D01*
G01X397800Y216600D02*
Y212200D01*
X393400Y207800D01*
Y196650D01*
X391100Y194350D01*
Y192390D01*
X392600Y190890D01*
Y190600D01*
G01X396200Y194700D02*
Y194900D01*
X396600Y195300D01*
Y203500D01*
X404000Y210900D01*
G01X397307Y186607D02*
X397333D01*
X399800Y189074D01*
Y202200D01*
X408425Y210825D01*
G01X405900Y121700D02*
Y121252D01*
X407600Y119552D01*
Y114169D01*
X409469Y112300D01*
X415168D01*
X424596Y102872D01*
X435672D01*
G01X409110Y114910D02*
X410857Y113163D01*
X415437D01*
X420800Y107800D01*
X430200D01*
X433700Y104300D01*
X436000D01*
X437000Y103300D01*
X446400D01*
X446900Y103800D01*
G01X435400Y98400D02*
X435251Y98549D01*
X433549D01*
X431098Y101000D01*
X424204D01*
X414541Y110663D01*
X408842D01*
X405200Y114305D01*
Y115343D01*
G01X409196Y118195D02*
X410800Y116591D01*
Y115000D01*
X411837Y113963D01*
X415837D01*
X421000Y108800D01*
X430700D01*
X433900Y105600D01*
X437300D01*
X438350Y104550D01*
X445550D01*
X446700Y105700D01*
G01X404900Y124600D02*
X406049D01*
X408289Y122360D01*
X409711D01*
X410560Y121511D01*
Y120448D01*
X412908Y118100D01*
X418400D01*
X420100Y116400D01*
Y115115D01*
X424574Y110641D01*
X432678D01*
X434019Y109300D01*
X441200D01*
G01X404529Y118507D02*
X404507D01*
X403400Y117400D01*
Y114592D01*
X408229Y109763D01*
X414309D01*
X423872Y100200D01*
X430766D01*
X434116Y96850D01*
X435600D01*
G01X441200Y108000D02*
X432900D01*
X431200Y109700D01*
X421300D01*
X415287Y115713D01*
X412462D01*
G01X406200Y127400D02*
X406550Y127750D01*
X413150D01*
X416289Y124611D01*
X432654D01*
X433690Y125647D01*
X440620D01*
X441000Y125267D01*
G01X439813Y157600D02*
X438894D01*
X438281Y156987D01*
X419635D01*
X414800Y161822D01*
Y162600D01*
G01X414572Y165913D02*
X416545D01*
X419235Y163223D01*
Y159651D01*
X420299Y158587D01*
X435638D01*
X436575Y159524D01*
Y160268D01*
X439044Y162737D01*
X441200D01*
G01X411800Y162700D02*
X415850Y159450D01*
X419113Y156187D01*
X441700D01*
G01X411356Y165732D02*
X411567D01*
X413249Y164050D01*
X415508D01*
X416335Y163223D01*
Y161420D01*
X419967Y157787D01*
X436111D01*
X437475Y159151D01*
Y159895D01*
X438780Y161200D01*
X440500D01*
G01X403600Y182400D02*
X403781Y182219D01*
X408487D01*
X409831Y183563D01*
X413031D01*
X413700Y184232D01*
Y193732D01*
X414250Y194282D01*
Y197450D01*
X415400Y198600D01*
X417517D01*
X419003Y200086D01*
Y204035D01*
X420268Y205300D01*
X423132D01*
X427632Y200800D01*
X428450D01*
G01X403600Y180200D02*
X403900D01*
X405119Y181419D01*
X408819D01*
X410163Y182763D01*
X413363D01*
X414500Y183900D01*
Y193400D01*
X415050Y193950D01*
Y197118D01*
X415732Y197800D01*
X417849D01*
X419803Y199754D01*
Y203703D01*
X420600Y204500D01*
X422800D01*
X427300Y200000D01*
X427600D01*
X428450Y199150D01*
G01X403022Y192094D02*
Y192792D01*
X404560Y194330D01*
Y195750D01*
X404200Y196110D01*
Y201800D01*
X413274Y210874D01*
X418211D01*
X421022Y213685D01*
X421704D01*
X421717Y213698D01*
G01X402967Y195005D02*
X403400Y195438D01*
Y202132D01*
X412942Y211674D01*
X417879D01*
X421300Y215095D01*
Y215615D01*
G01X408100Y193600D02*
X407716Y193984D01*
Y195084D01*
X408400Y195768D01*
Y202668D01*
X414431Y208699D01*
X421599D01*
X423933Y211033D01*
X424667D01*
G01X408200Y190500D02*
X406400Y192300D01*
Y194900D01*
X407600Y196100D01*
Y203000D01*
X414099Y209499D01*
X421267D01*
X423500Y211732D01*
Y212200D01*
G01X408242Y184624D02*
X407400Y185466D01*
Y187400D01*
X407900Y187900D01*
X409600D01*
X410600Y188900D01*
Y201366D01*
X412234Y203000D01*
X415487D01*
X418987Y206500D01*
X425795D01*
X426271Y206024D01*
G01Y207674D02*
X425897Y207300D01*
X418655D01*
X415155Y203800D01*
X411902D01*
X409800Y201698D01*
Y189232D01*
X409268Y188700D01*
X407568D01*
X406600Y187732D01*
Y186200D01*
X405376Y184976D01*
X405231D01*
G01X428100Y120000D02*
Y119200D01*
X429600Y117700D01*
Y115292D01*
X430746Y114146D01*
X432049D01*
X435300Y110895D01*
X439995D01*
G01X424900Y121213D02*
X425487Y121800D01*
X432700D01*
X435900Y118600D01*
X440900D01*
X442000Y117500D01*
G01X441480Y165437D02*
X441246Y165203D01*
X438698D01*
X435795Y162300D01*
X433532D01*
X432829Y163003D01*
X425898D01*
X424795Y161900D01*
X421563D01*
X420804Y162659D01*
G01X431220Y168600D02*
X430832Y168420D01*
X429950Y167850D01*
X429680Y167100D01*
G02X429614Y166696I-2080J132D01*
G01X428800Y165900D01*
X428232Y165545D01*
G02X427450Y165221I-782J782D01*
G01X423945D01*
G01X441653Y164337D02*
X441312D01*
X441246Y164403D01*
X439030D01*
X436127Y161500D01*
X433200D01*
X432497Y162203D01*
X426230D01*
X425127Y161100D01*
X421963D01*
X420900Y160037D01*
G01X429310Y174940D02*
X426500D01*
X425047Y174786D01*
X423860Y173599D01*
Y169280D01*
X421810Y167230D01*
X421710D01*
G54D11*
G01X10636Y-27865D02*
G02I-12000J0D01*
G01X14636D02*
X-17364D01*
G01X5486D02*
G02I-6850J0D01*
G01X-1364Y-43865D02*
Y-11865D01*
G01X14636Y-43865D02*
Y-123865D01*
G01D02*
X1309236D01*
G01X14636Y-79365D02*
X1309236D01*
G01X14636Y-43865D02*
X1309236D01*
G01X15000Y127500D02*
X31400D01*
X37200Y121700D01*
X41578D01*
X43678Y123800D01*
X65500D01*
G01X60800Y87500D02*
X54800Y93500D01*
X48800D01*
X41500Y100800D01*
G01X116500Y211200D02*
X116100Y211600D01*
X112400D01*
X102900Y221100D01*
X100600D01*
G01X180700Y78500D02*
Y77523D01*
X168177Y65000D01*
X164000D01*
G01X258634Y95850D02*
Y95834D01*
X255325Y92525D01*
X247020D01*
X238545Y84050D01*
X233764D01*
X230114Y80400D01*
X221815D01*
X216261Y74846D01*
G01X212600Y161500D02*
X218000D01*
X220000Y159500D01*
X237912D01*
X244537Y166125D01*
X253942D01*
X257687Y169870D01*
G01X258400Y65600D02*
X260901D01*
X260975Y65674D01*
X278574D01*
X295200Y82300D01*
X299800D01*
G01X521736Y-43865D02*
Y-123865D01*
G01X659236Y-43865D02*
Y-123865D01*
G01X656200Y144000D02*
Y125000D01*
X653600Y122400D01*
G01X750100Y16100D02*
X749841Y16359D01*
Y37659D01*
X727500Y60000D01*
Y82000D01*
X718900Y90600D01*
Y94000D01*
G01X754000Y115100D02*
X748600Y109700D01*
X725500D01*
X724200Y108400D01*
G01X804032Y57032D02*
X811000Y50064D01*
Y24000D01*
X805499Y18499D01*
X786499D01*
X778007Y10007D01*
X756193D01*
X750100Y16100D01*
G01X766600Y139800D02*
X766200Y139400D01*
X758400D01*
X754500Y135500D01*
Y115600D01*
X754000Y115100D01*
G01X756400Y110500D02*
X756700D01*
X758000Y111800D01*
Y119500D01*
X767000Y128500D01*
Y134873D01*
X771300Y139173D01*
Y140200D01*
G01X774236Y-43865D02*
Y-123865D01*
G01X941736Y-43865D02*
Y-123865D01*
G01X1111736Y-43865D02*
Y-123865D01*
G01X1309236Y-43865D02*
Y-123865D01*
G01X1341236Y-27865D02*
X1309236D01*
G01X1337236D02*
G02I-12000J0D01*
G01X1332086D02*
G02I-6850J0D01*
G01X1325236Y-43865D02*
Y-11865D01*
X17500Y190200D03*
X17301Y212401D03*
X17300Y218307D03*
X10000Y229500D03*
X16400Y224212D03*
X16118Y230118D03*
X10194Y243106D03*
X9500Y234200D03*
X16899Y241929D03*
X16300Y236023D03*
X10190Y258510D03*
X10194Y254917D03*
X10190Y246699D03*
X16899Y247834D03*
Y253740D03*
Y259645D03*
X7600Y268100D03*
X16899Y265551D03*
X32800Y120400D03*
X25800Y120300D03*
X29200D03*
X30000Y196200D03*
X21900Y205400D03*
X31500Y207500D03*
X41500Y100800D03*
X40500Y127700D03*
X38500Y148000D03*
X48500D03*
X41000Y152300D03*
Y143300D03*
X46000D03*
Y152300D03*
X43500Y148000D03*
Y138500D03*
X48500D03*
X38500D03*
X45800Y158100D03*
X34800Y198800D03*
X37900Y195300D03*
X34800Y203700D03*
X37600Y212700D03*
Y207800D03*
X34500Y216000D03*
X40400Y217100D03*
X37900Y219000D03*
Y222500D03*
Y229500D03*
Y226000D03*
Y240000D03*
Y243500D03*
Y233000D03*
X38000Y236500D03*
X40500Y260000D03*
X37900Y257500D03*
Y254000D03*
Y247000D03*
X38000Y250500D03*
X60800Y87500D03*
X52500Y96500D03*
Y106500D03*
X57500Y96500D03*
X60000Y101500D03*
X50000D03*
X55000D03*
X57500Y106500D03*
X60000Y111300D03*
X50000D03*
X55000D03*
X58800Y177000D03*
X51860Y187640D03*
Y191410D03*
X59379Y184380D03*
X55720D03*
X56724Y243300D03*
X56800Y249613D03*
X58102Y246471D03*
X78300Y64300D03*
X65500Y123800D03*
X79500Y230000D03*
X78700Y259800D03*
X67600Y255800D03*
X66300Y259300D03*
X78200Y275600D03*
X67000Y263200D03*
X89400Y58200D03*
X83600Y57600D03*
X84500Y230000D03*
X89500D03*
X84500Y225000D03*
Y235000D03*
X91400Y270300D03*
X104400Y57700D03*
X96800Y53300D03*
X99600Y225700D03*
X100600Y221100D03*
X99328Y235370D03*
X109000Y231400D03*
X120200Y45610D03*
X121170Y80900D03*
X121295Y77502D03*
X126000Y86200D03*
X125787Y78813D03*
X118500Y125500D03*
X125000Y178000D03*
X138000Y49800D03*
X134200Y86100D03*
X137138Y76512D03*
X129300Y84900D03*
X136600Y93300D03*
X136500Y104923D03*
X136540Y108620D03*
X126950Y125200D03*
X138600Y146300D03*
X143688Y48350D03*
X150894Y76497D03*
X154294Y76506D03*
X150670Y102720D03*
X154550Y106200D03*
X151080Y99344D03*
X154550Y102800D03*
X153693Y124807D03*
X146400Y138595D03*
X150500Y183000D03*
X164000Y65000D03*
X172199Y91591D03*
X158305Y112180D03*
X158500Y161820D03*
X162000Y226000D03*
X167000D03*
Y221500D03*
X162000D03*
Y230500D03*
X167000D03*
X162000Y235000D03*
X180700Y78500D03*
X179400Y94200D03*
X178000Y97300D03*
X177200Y148700D03*
X181000Y167500D03*
X176800Y241600D03*
X197700Y54400D03*
X194700D03*
X188900Y91800D03*
X189106Y97235D03*
X201650Y111200D03*
X205300Y54900D03*
X208700D03*
X214942Y67242D03*
X211600Y82100D03*
X212300Y85500D03*
X209259Y113771D03*
Y117430D03*
X206605Y121741D03*
X209900Y120900D03*
X205920Y221550D03*
X229300Y42950D03*
X219900Y39100D03*
X230400Y63000D03*
X223800Y61700D03*
X230875Y106300D03*
X227894Y104600D03*
X227800Y101200D03*
X228000Y108304D03*
X227870Y170252D03*
X227000Y275500D03*
X243200Y73700D03*
X240300Y67200D03*
X244800Y100700D03*
X244715Y159785D03*
X239900Y180600D03*
X240119Y183993D03*
X259000Y57800D03*
X250500Y57900D03*
X262000Y57800D03*
X253500Y57900D03*
X264500Y73100D03*
X264125Y79350D03*
X259820Y103454D03*
X262131Y100959D03*
X258634Y95850D03*
X264600Y173100D03*
X257687Y169870D03*
X262700Y191500D03*
X269800Y44800D03*
X275200Y78700D03*
X275900Y88200D03*
X275400Y237900D03*
X288400Y94200D03*
X288100Y99500D03*
X281475Y116475D03*
X291201Y225025D03*
X287802Y225200D03*
X287600Y238100D03*
X287400Y254100D03*
X287250Y269250D03*
X300900Y46900D03*
X299800Y82300D03*
X301300Y97000D03*
X299300Y98500D03*
X296564Y136311D03*
X301109Y146156D03*
X310579Y182800D03*
X306612Y171882D03*
X304400Y182000D03*
X302591Y173906D03*
X309112Y171960D03*
X309200Y180500D03*
X305091Y173888D03*
X301745Y181788D03*
X307200Y182000D03*
X296600Y189100D03*
X314800Y48625D03*
X311950Y50800D03*
X312150Y100682D03*
X315500Y254100D03*
X322500Y254200D03*
X319000D03*
X316945Y281606D03*
X316400Y276800D03*
X327577Y48475D03*
X356432Y43657D03*
X356971Y37700D03*
X349900Y263800D03*
X342600Y277900D03*
X367497Y41042D03*
X371457Y37642D03*
X367520D03*
X366484Y47129D03*
X362626Y47068D03*
X425400Y9103D03*
X422000D03*
X428800D03*
X432200D03*
X433129Y245783D03*
X426600Y274100D03*
X429900Y274940D03*
X441281Y17025D03*
X436600Y275000D03*
X464000Y275200D03*
X460400D03*
X480400Y154050D03*
X467100Y154200D03*
X477000Y154050D03*
X470100Y154200D03*
X473500Y154050D03*
X469000Y275200D03*
X472400Y275100D03*
X483800Y154050D03*
X487200Y154100D03*
X524700Y119500D03*
X515000Y119270D03*
X524700Y145041D03*
X518200Y183400D03*
X552100Y136000D03*
X557100D03*
X548354Y183600D03*
X572100Y136000D03*
X567100D03*
X562000Y127800D03*
X562100Y136000D03*
X562000Y144900D03*
X564398Y183481D03*
X584800Y183300D03*
X599300Y119270D03*
X593400Y126000D03*
X588800Y145000D03*
X592200D03*
X599200D03*
X612120Y121750D03*
X608360Y121800D03*
X617700Y125500D03*
X605600Y186650D03*
X627500Y104900D03*
X620000Y112575D03*
X639500Y136490D03*
X648500Y162600D03*
X653600Y122400D03*
X656200Y144000D03*
X661600Y156700D03*
X676200Y181600D03*
X684700Y179800D03*
X698000Y181500D03*
X701245Y183800D03*
X718900Y94000D03*
X726800Y95500D03*
X724200Y108400D03*
X724400Y176025D03*
X715500Y205837D03*
X730200Y94900D03*
X740300Y164700D03*
X727800Y176600D03*
X750100Y16100D03*
X754000Y115100D03*
X743100Y195500D03*
X758916Y104250D03*
X762304Y103957D03*
X771300Y140200D03*
X766600Y139800D03*
X787600Y183300D03*
X787800Y179900D03*
G54D21*
G01X70851Y-113865D02*
Y-96365D01*
G01X80021D02*
Y-113865D01*
G01Y-105115D02*
X70851D01*
G01X92936Y-113865D02*
X91626Y-113573D01*
X90316Y-112407D01*
X89442Y-110365D01*
X89006Y-108032D01*
X89442Y-105698D01*
X90316Y-103657D01*
X91626Y-102490D01*
X92936Y-102199D01*
X94246Y-102490D01*
X95556Y-103657D01*
X96429Y-105698D01*
X96648Y-108032D01*
X96429Y-110365D01*
X95556Y-112407D01*
X94246Y-113573D01*
X92936Y-113865D01*
G01X106724D02*
Y-102199D01*
G01Y-105115D02*
X107598Y-103657D01*
X108908Y-102490D01*
X110654Y-102199D01*
X112182Y-102490D01*
X113493Y-103657D01*
X114148Y-105698D01*
Y-113865D01*
G01X124661Y-105990D02*
X131648D01*
X130993Y-103948D01*
X129901Y-102782D01*
X128373Y-102199D01*
X126844Y-102490D01*
X125534Y-103365D01*
X124661Y-105407D01*
X124224Y-107157D01*
Y-108907D01*
X124661Y-110657D01*
X125753Y-112407D01*
X127063Y-113573D01*
X128591Y-113865D01*
X130119Y-113282D01*
X131648Y-111532D01*
G01X140851Y-119115D02*
X142161Y-119698D01*
X143908Y-119115D01*
X144999Y-117949D01*
X145873Y-116490D01*
X147182Y-111824D01*
X150021Y-102199D01*
G01X143034D02*
X147182Y-111824D01*
G01X182182Y-104532D02*
X183056Y-103657D01*
X183711Y-102199D01*
X184148Y-100156D01*
X183711Y-98407D01*
X182838Y-97240D01*
X181309Y-96365D01*
X175414D01*
Y-113865D01*
X182619D01*
X184148Y-112699D01*
X185021Y-110948D01*
X185458Y-108907D01*
X185021Y-106865D01*
X183711Y-105115D01*
X182182Y-104532D01*
X175414D01*
G01X201866Y-113865D02*
Y-102199D01*
G01Y-104240D02*
X200993Y-103074D01*
X199682Y-102490D01*
X198154Y-102199D01*
X196626Y-102782D01*
X195316Y-103948D01*
X194442Y-105698D01*
X194006Y-108032D01*
X194442Y-110365D01*
X195316Y-112115D01*
X196626Y-113282D01*
X198154Y-113865D01*
X199682Y-113573D01*
X200993Y-112699D01*
X201866Y-111532D01*
G01X219366Y-96365D02*
Y-113865D01*
G01Y-111241D02*
X218493Y-112699D01*
X217182Y-113573D01*
X215654Y-113865D01*
X213908Y-113282D01*
X212598Y-111824D01*
X211724Y-110074D01*
X211506Y-108032D01*
X211724Y-105990D01*
X212598Y-104240D01*
X213908Y-102782D01*
X215654Y-102199D01*
X217182Y-102490D01*
X218274Y-103074D01*
X219366Y-104240D01*
G01X229879Y-118240D02*
X231408Y-119407D01*
X233154Y-119698D01*
X234682Y-119407D01*
X235993Y-117949D01*
X236866Y-115907D01*
Y-102199D01*
G01Y-104532D02*
X235993Y-103365D01*
X234682Y-102490D01*
X233154Y-102199D01*
X231408Y-102782D01*
X230316Y-103948D01*
X229442Y-105990D01*
X229006Y-108032D01*
X229224Y-109782D01*
X230098Y-111824D01*
X231408Y-113282D01*
X233154Y-113865D01*
X234464Y-113573D01*
X235993Y-112407D01*
X236866Y-111241D01*
G01X247161Y-105990D02*
X254148D01*
X253493Y-103948D01*
X252401Y-102782D01*
X250873Y-102199D01*
X249344Y-102490D01*
X248034Y-103365D01*
X247161Y-105407D01*
X246724Y-107157D01*
Y-108907D01*
X247161Y-110657D01*
X248253Y-112407D01*
X249563Y-113573D01*
X251091Y-113865D01*
X252619Y-113282D01*
X254148Y-111532D01*
G01X264879Y-113865D02*
Y-102199D01*
G01Y-104532D02*
X265971Y-103365D01*
X267063Y-102490D01*
X268591Y-102199D01*
X269682Y-102490D01*
X270993Y-103365D01*
G01X298569Y-113865D02*
Y-96365D01*
X303809D01*
X305556Y-97240D01*
X306866Y-99282D01*
X307303Y-101615D01*
X306866Y-103948D01*
X305774Y-105698D01*
X303809Y-106574D01*
X298569D01*
G01X324366Y-113865D02*
Y-102199D01*
G01Y-104240D02*
X323493Y-103074D01*
X322182Y-102490D01*
X320654Y-102199D01*
X319126Y-102782D01*
X317816Y-103948D01*
X316942Y-105698D01*
X316506Y-108032D01*
X316942Y-110365D01*
X317816Y-112115D01*
X319126Y-113282D01*
X320654Y-113865D01*
X322182Y-113573D01*
X323493Y-112699D01*
X324366Y-111532D01*
G01X334224Y-113865D02*
Y-102199D01*
G01Y-105115D02*
X335098Y-103657D01*
X336408Y-102490D01*
X338154Y-102199D01*
X339682Y-102490D01*
X340993Y-103657D01*
X341648Y-105698D01*
Y-113865D01*
G01X355436Y-96365D02*
Y-113865D01*
G01X352379Y-102199D02*
X358493D01*
G01X369224Y-113865D02*
Y-96365D01*
G01Y-104823D02*
X370316Y-103365D01*
X371408Y-102490D01*
X373154Y-102199D01*
X374464Y-102490D01*
X375993Y-103657D01*
X376648Y-105407D01*
Y-113865D01*
G01X387161Y-105990D02*
X394148D01*
X393493Y-103948D01*
X392401Y-102782D01*
X390873Y-102199D01*
X389344Y-102490D01*
X388034Y-103365D01*
X387161Y-105407D01*
X386724Y-107157D01*
Y-108907D01*
X387161Y-110657D01*
X388253Y-112407D01*
X389563Y-113573D01*
X391091Y-113865D01*
X392619Y-113282D01*
X394148Y-111532D01*
G01X404879Y-113865D02*
Y-102199D01*
G01Y-104532D02*
X405971Y-103365D01*
X407063Y-102490D01*
X408591Y-102199D01*
X409682Y-102490D01*
X410993Y-103365D01*
G01X437259Y-113865D02*
Y-96365D01*
X442936Y-110948D01*
X448613Y-96365D01*
Y-113865D01*
G01X462182Y-104532D02*
X463056Y-103657D01*
X463711Y-102199D01*
X464148Y-100156D01*
X463711Y-98407D01*
X462838Y-97240D01*
X461309Y-96365D01*
X455414D01*
Y-113865D01*
X462619D01*
X464148Y-112699D01*
X465021Y-110948D01*
X465458Y-108907D01*
X465021Y-106865D01*
X463711Y-105115D01*
X462182Y-104532D01*
X455414D01*
G01X227259Y-68865D02*
Y-51365D01*
X232936Y-65948D01*
X238613Y-51365D01*
Y-68865D01*
G01X250436D02*
X249126Y-68573D01*
X247816Y-67407D01*
X246942Y-65365D01*
X246506Y-63032D01*
X246942Y-60698D01*
X247816Y-58657D01*
X249126Y-57490D01*
X250436Y-57199D01*
X251746Y-57490D01*
X253056Y-58657D01*
X253929Y-60698D01*
X254148Y-63032D01*
X253929Y-65365D01*
X253056Y-67407D01*
X251746Y-68573D01*
X250436Y-68865D01*
G01X271866Y-51365D02*
Y-68865D01*
G01Y-66241D02*
X270993Y-67699D01*
X269682Y-68573D01*
X268154Y-68865D01*
X266408Y-68282D01*
X265098Y-66824D01*
X264224Y-65074D01*
X264006Y-63032D01*
X264224Y-60990D01*
X265098Y-59240D01*
X266408Y-57782D01*
X268154Y-57199D01*
X269682Y-57490D01*
X270774Y-58074D01*
X271866Y-59240D01*
G01X282161Y-60990D02*
X289148D01*
X288493Y-58948D01*
X287401Y-57782D01*
X285873Y-57199D01*
X284344Y-57490D01*
X283034Y-58365D01*
X282161Y-60407D01*
X281724Y-62157D01*
Y-63907D01*
X282161Y-65657D01*
X283253Y-67407D01*
X284563Y-68573D01*
X286091Y-68865D01*
X287619Y-68282D01*
X289148Y-66532D01*
G01X302936Y-68865D02*
Y-51365D01*
G01X542319Y-68865D02*
Y-51365D01*
X547559D01*
X549306Y-52240D01*
X550616Y-54282D01*
X551053Y-56615D01*
X550616Y-58948D01*
X549524Y-60698D01*
X547559Y-61574D01*
X542319D01*
G01X568989Y-52824D02*
X567679Y-51948D01*
X566151Y-51365D01*
X564404D01*
X562439Y-52240D01*
X560911Y-53698D01*
X559819Y-55449D01*
X558946Y-58365D01*
X558727Y-60990D01*
X559164Y-63615D01*
X559819Y-65365D01*
X561129Y-67115D01*
X562658Y-68282D01*
X564186Y-68865D01*
X565714D01*
X567243Y-68282D01*
X568553Y-67407D01*
X569645Y-66241D01*
G01X583432Y-59532D02*
X584306Y-58657D01*
X584961Y-57199D01*
X585398Y-55156D01*
X584961Y-53407D01*
X584088Y-52240D01*
X582559Y-51365D01*
X576664D01*
Y-68865D01*
X583869D01*
X585398Y-67699D01*
X586271Y-65948D01*
X586708Y-63907D01*
X586271Y-61865D01*
X584961Y-60115D01*
X583432Y-59532D01*
X576664D01*
G01X592636Y-74698D02*
X605736D01*
G01X611664Y-68865D02*
Y-51365D01*
X621708Y-68865D01*
Y-51365D01*
G01X634186Y-68865D02*
X632439Y-68573D01*
X630911Y-67407D01*
X629601Y-65657D01*
X628727Y-63615D01*
X628291Y-61282D01*
Y-58948D01*
X628727Y-56615D01*
X629601Y-54573D01*
X630911Y-52824D01*
X632439Y-51657D01*
X634186Y-51365D01*
X635932Y-51657D01*
X637461Y-52824D01*
X638771Y-54573D01*
X639645Y-56615D01*
X640081Y-58948D01*
Y-61282D01*
X639645Y-63615D01*
X638771Y-65657D01*
X637461Y-67407D01*
X635932Y-68573D01*
X634186Y-68865D01*
G01X555436Y-113865D02*
Y-96365D01*
X552816Y-99865D01*
G01Y-113865D02*
X558056D01*
G01X568133Y-110365D02*
X569442Y-112407D01*
X571189Y-113573D01*
X573154Y-113865D01*
X574901Y-113573D01*
X576648Y-112115D01*
X577739Y-110365D01*
X577958Y-108615D01*
X577521Y-106574D01*
X575993Y-105115D01*
X574464Y-104532D01*
X572499D01*
G01X574464D02*
X575774Y-103657D01*
X576866Y-102199D01*
X577303Y-100449D01*
X576866Y-98698D01*
X575774Y-97240D01*
X573809Y-96365D01*
X571844Y-96657D01*
X569879Y-97824D01*
G01X590436Y-113865D02*
Y-96365D01*
X587816Y-99865D01*
G01Y-113865D02*
X593056D01*
G01X603133Y-110365D02*
X604442Y-112407D01*
X606189Y-113573D01*
X608154Y-113865D01*
X609901Y-113573D01*
X611648Y-112115D01*
X612739Y-110365D01*
X612958Y-108615D01*
X612521Y-106574D01*
X610993Y-105115D01*
X609464Y-104532D01*
X607499D01*
G01X609464D02*
X610774Y-103657D01*
X611866Y-102199D01*
X612303Y-100449D01*
X611866Y-98698D01*
X610774Y-97240D01*
X608809Y-96365D01*
X606844Y-96657D01*
X604879Y-97824D01*
G01X625436Y-96365D02*
X623689Y-96948D01*
X622379Y-98407D01*
X621506Y-100156D01*
X620851Y-102490D01*
X620633Y-105115D01*
X620851Y-107740D01*
X621506Y-110074D01*
X622379Y-111824D01*
X623689Y-113282D01*
X625436Y-113865D01*
X627182Y-113282D01*
X628493Y-111824D01*
X629366Y-110074D01*
X630021Y-107740D01*
X630239Y-105115D01*
X630021Y-102490D01*
X629366Y-100156D01*
X628493Y-98407D01*
X627182Y-96948D01*
X625436Y-96365D01*
G01X685027Y-51365D02*
X690486Y-68865D01*
X695945Y-51365D01*
G01X712353Y-68865D02*
X703619D01*
Y-51365D01*
X712353D01*
G01X708859Y-59823D02*
X703619D01*
G01X721119Y-68865D02*
Y-51365D01*
X726578D01*
X728324Y-52240D01*
X729416Y-53407D01*
X729853Y-55740D01*
X729416Y-58074D01*
X728106Y-59532D01*
X726578Y-60407D01*
X721119D01*
G01X726578D02*
X729853Y-68865D01*
G01X742986Y-69448D02*
X742549Y-69157D01*
Y-68573D01*
X742986Y-68282D01*
X743423Y-68573D01*
Y-69157D01*
X742986Y-69448D01*
G01X707986Y-113865D02*
Y-96365D01*
X705366Y-99865D01*
G01Y-113865D02*
X710606D01*
G01X727232Y-104532D02*
X728106Y-103657D01*
X728761Y-102199D01*
X729198Y-100156D01*
X728761Y-98407D01*
X727888Y-97240D01*
X726359Y-96365D01*
X720464D01*
Y-113865D01*
X727669D01*
X729198Y-112699D01*
X730071Y-110948D01*
X730508Y-108907D01*
X730071Y-106865D01*
X728761Y-105115D01*
X727232Y-104532D01*
X720464D01*
G01X818569Y-51365D02*
Y-68865D01*
X827303D01*
G01X844366D02*
Y-57199D01*
G01Y-59240D02*
X843493Y-58074D01*
X842182Y-57490D01*
X840654Y-57199D01*
X839126Y-57782D01*
X837816Y-58948D01*
X836942Y-60698D01*
X836506Y-63032D01*
X836942Y-65365D01*
X837816Y-67115D01*
X839126Y-68282D01*
X840654Y-68865D01*
X842182Y-68573D01*
X843493Y-67699D01*
X844366Y-66532D01*
G01X853351Y-74115D02*
X854661Y-74698D01*
X856408Y-74115D01*
X857499Y-72949D01*
X858373Y-71490D01*
X859682Y-66824D01*
X862521Y-57199D01*
G01X855534D02*
X859682Y-66824D01*
G01X872161Y-60990D02*
X879148D01*
X878493Y-58948D01*
X877401Y-57782D01*
X875873Y-57199D01*
X874344Y-57490D01*
X873034Y-58365D01*
X872161Y-60407D01*
X871724Y-62157D01*
Y-63907D01*
X872161Y-65657D01*
X873253Y-67407D01*
X874563Y-68573D01*
X876091Y-68865D01*
X877619Y-68282D01*
X879148Y-66532D01*
G01X889879Y-68865D02*
Y-57199D01*
G01Y-59532D02*
X890971Y-58365D01*
X892063Y-57490D01*
X893591Y-57199D01*
X894682Y-57490D01*
X895993Y-58365D01*
G01X871053Y-96365D02*
Y-113865D01*
X862319D01*
G01X849186D02*
X847658Y-113573D01*
X845911Y-112699D01*
X844819Y-111241D01*
X844383Y-109198D01*
X844819Y-107157D01*
X846129Y-105407D01*
X848094Y-104532D01*
X850278D01*
X851588Y-103948D01*
X852680Y-102490D01*
X853116Y-100449D01*
X852461Y-98407D01*
X850933Y-96948D01*
X849186Y-96365D01*
X847440Y-96948D01*
X845911Y-98407D01*
X845256Y-100449D01*
X845693Y-102490D01*
X846784Y-103948D01*
X848094Y-104532D01*
X850278D01*
X852243Y-105407D01*
X853553Y-107157D01*
X853989Y-109198D01*
X853553Y-111241D01*
X852461Y-112699D01*
X850714Y-113573D01*
X849186Y-113865D01*
G01X943619Y-110365D02*
X944711Y-112115D01*
X946021Y-113282D01*
X947549Y-113865D01*
X949296Y-113282D01*
X950606Y-112115D01*
X951916Y-110365D01*
X952353Y-108032D01*
Y-96365D01*
G01X965486Y-113865D02*
X963739Y-113573D01*
X962211Y-112407D01*
X960901Y-110657D01*
X960027Y-108615D01*
X959591Y-106282D01*
Y-103948D01*
X960027Y-101615D01*
X960901Y-99573D01*
X962211Y-97824D01*
X963739Y-96657D01*
X965486Y-96365D01*
X967232Y-96657D01*
X968761Y-97824D01*
X970071Y-99573D01*
X970945Y-101615D01*
X971381Y-103948D01*
Y-106282D01*
X970945Y-108615D01*
X970071Y-110657D01*
X968761Y-112407D01*
X967232Y-113573D01*
X965486Y-113865D01*
G01X978401Y-111532D02*
X980148Y-112990D01*
X982113Y-113865D01*
X983859D01*
X985606Y-112990D01*
X986916Y-111532D01*
X987571Y-109490D01*
X987134Y-107449D01*
X986043Y-105698D01*
X984078Y-104532D01*
X981458Y-103948D01*
X979929Y-102782D01*
X979274Y-100740D01*
X979711Y-98698D01*
X980803Y-97240D01*
X982331Y-96365D01*
X983859D01*
X985388Y-96948D01*
X986698Y-98407D01*
G01X1004853Y-113865D02*
X996119D01*
Y-96365D01*
X1004853D01*
G01X1001359Y-104823D02*
X996119D01*
G01X1013619Y-113865D02*
Y-96365D01*
X1018859D01*
X1020606Y-97240D01*
X1021916Y-99282D01*
X1022353Y-101615D01*
X1021916Y-103948D01*
X1020824Y-105698D01*
X1018859Y-106574D01*
X1013619D01*
G01X1030901Y-113865D02*
Y-96365D01*
G01X1040071D02*
Y-113865D01*
G01Y-105115D02*
X1030901D01*
G01X1066119Y-96365D02*
Y-113865D01*
X1074853D01*
G01X1082527D02*
X1087986Y-96365D01*
X1093445Y-113865D01*
G01X1091479Y-107740D02*
X1084492D01*
G01X1100683Y-96365D02*
Y-108907D01*
X1101556Y-111532D01*
X1103303Y-113282D01*
X1105486Y-113865D01*
X1107669Y-113282D01*
X1109416Y-111532D01*
X1110289Y-108907D01*
Y-96365D01*
G01X960683Y-68865D02*
Y-51365D01*
X965049D01*
X966796Y-52240D01*
X968106Y-53407D01*
X969198Y-55156D01*
X970071Y-57199D01*
X970289Y-60115D01*
X970071Y-63032D01*
X969198Y-65074D01*
X968106Y-66824D01*
X966796Y-67990D01*
X965049Y-68865D01*
X960683D01*
G01X979711Y-60990D02*
X986698D01*
X986043Y-58948D01*
X984951Y-57782D01*
X983423Y-57199D01*
X981894Y-57490D01*
X980584Y-58365D01*
X979711Y-60407D01*
X979274Y-62157D01*
Y-63907D01*
X979711Y-65657D01*
X980803Y-67407D01*
X982113Y-68573D01*
X983641Y-68865D01*
X985169Y-68282D01*
X986698Y-66532D01*
G01X997211Y-66824D02*
X998303Y-67990D01*
X999831Y-68865D01*
X1001141D01*
X1002451Y-68282D01*
X1003324Y-67407D01*
X1003761Y-66241D01*
X1003543Y-64490D01*
X1002669Y-63615D01*
X998739Y-61865D01*
X997866Y-59823D01*
X998303Y-58365D01*
X999176Y-57490D01*
X1000486Y-57199D01*
X1001796Y-57490D01*
X1003106Y-58365D01*
G01X1017986Y-57199D02*
Y-68865D01*
G01Y-52532D02*
X1017549Y-52240D01*
Y-51657D01*
X1017986Y-51365D01*
X1018423Y-51657D01*
Y-52240D01*
X1017986Y-52532D01*
G01X1032429Y-73240D02*
X1033958Y-74407D01*
X1035704Y-74698D01*
X1037232Y-74407D01*
X1038543Y-72949D01*
X1039416Y-70907D01*
Y-57199D01*
G01Y-59532D02*
X1038543Y-58365D01*
X1037232Y-57490D01*
X1035704Y-57199D01*
X1033958Y-57782D01*
X1032866Y-58948D01*
X1031992Y-60990D01*
X1031556Y-63032D01*
X1031774Y-64782D01*
X1032648Y-66824D01*
X1033958Y-68282D01*
X1035704Y-68865D01*
X1037014Y-68573D01*
X1038543Y-67407D01*
X1039416Y-66241D01*
G01X1049274Y-68865D02*
Y-57199D01*
G01Y-60115D02*
X1050148Y-58657D01*
X1051458Y-57490D01*
X1053204Y-57199D01*
X1054732Y-57490D01*
X1056043Y-58657D01*
X1056698Y-60698D01*
Y-68865D01*
G01X1067211Y-60990D02*
X1074198D01*
X1073543Y-58948D01*
X1072451Y-57782D01*
X1070923Y-57199D01*
X1069394Y-57490D01*
X1068084Y-58365D01*
X1067211Y-60407D01*
X1066774Y-62157D01*
Y-63907D01*
X1067211Y-65657D01*
X1068303Y-67407D01*
X1069613Y-68573D01*
X1071141Y-68865D01*
X1072669Y-68282D01*
X1074198Y-66532D01*
G01X1084929Y-68865D02*
Y-57199D01*
G01Y-59532D02*
X1086021Y-58365D01*
X1087113Y-57490D01*
X1088641Y-57199D01*
X1089732Y-57490D01*
X1091043Y-58365D01*
G01X1131686Y-113865D02*
Y-96365D01*
X1129066Y-99865D01*
G01Y-113865D02*
X1134306D01*
G01X1149186D02*
Y-96365D01*
X1146566Y-99865D01*
G01Y-113865D02*
X1151806D01*
G01X1162756Y-114448D02*
X1170616Y-96365D01*
G01X1184186Y-113865D02*
Y-96365D01*
X1181566Y-99865D01*
G01Y-113865D02*
X1186806D01*
G01X1196883Y-110365D02*
X1198192Y-112407D01*
X1199939Y-113573D01*
X1201904Y-113865D01*
X1203651Y-113573D01*
X1205398Y-112115D01*
X1206489Y-110365D01*
X1206708Y-108615D01*
X1206271Y-106574D01*
X1204743Y-105115D01*
X1203214Y-104532D01*
X1201249D01*
G01X1203214D02*
X1204524Y-103657D01*
X1205616Y-102199D01*
X1206053Y-100449D01*
X1205616Y-98698D01*
X1204524Y-97240D01*
X1202559Y-96365D01*
X1200594Y-96657D01*
X1198629Y-97824D01*
G01X1215256Y-114448D02*
X1223116Y-96365D01*
G01X1232538Y-99282D02*
X1233848Y-97532D01*
X1235376Y-96657D01*
X1237123Y-96365D01*
X1239306Y-96948D01*
X1240834Y-98407D01*
X1241271Y-100156D01*
X1241053Y-101907D01*
X1240179Y-103365D01*
X1235813Y-106282D01*
X1233848Y-108323D01*
X1232538Y-111241D01*
X1232101Y-113865D01*
X1241271D01*
G01X1254186Y-96365D02*
X1252439Y-96948D01*
X1251129Y-98407D01*
X1250256Y-100156D01*
X1249601Y-102490D01*
X1249383Y-105115D01*
X1249601Y-107740D01*
X1250256Y-110074D01*
X1251129Y-111824D01*
X1252439Y-113282D01*
X1254186Y-113865D01*
X1255932Y-113282D01*
X1257243Y-111824D01*
X1258116Y-110074D01*
X1258771Y-107740D01*
X1258989Y-105115D01*
X1258771Y-102490D01*
X1258116Y-100156D01*
X1257243Y-98407D01*
X1255932Y-96948D01*
X1254186Y-96365D01*
G01X1271686Y-113865D02*
Y-96365D01*
X1269066Y-99865D01*
G01Y-113865D02*
X1274306D01*
G01X1291806D02*
Y-96365D01*
X1283727Y-108907D01*
X1294645D01*
G01X1179383Y-68865D02*
Y-51365D01*
X1183749D01*
X1185496Y-52240D01*
X1186806Y-53407D01*
X1187898Y-55156D01*
X1188771Y-57199D01*
X1188989Y-60115D01*
X1188771Y-63032D01*
X1187898Y-65074D01*
X1186806Y-66824D01*
X1185496Y-67990D01*
X1183749Y-68865D01*
X1179383D01*
G01X1205616D02*
Y-57199D01*
G01Y-59240D02*
X1204743Y-58074D01*
X1203432Y-57490D01*
X1201904Y-57199D01*
X1200376Y-57782D01*
X1199066Y-58948D01*
X1198192Y-60698D01*
X1197756Y-63032D01*
X1198192Y-65365D01*
X1199066Y-67115D01*
X1200376Y-68282D01*
X1201904Y-68865D01*
X1203432Y-68573D01*
X1204743Y-67699D01*
X1205616Y-66532D01*
G01X1219186Y-51365D02*
Y-68865D01*
G01X1216129Y-57199D02*
X1222243D01*
G01X1233411Y-60990D02*
X1240398D01*
X1239743Y-58948D01*
X1238651Y-57782D01*
X1237123Y-57199D01*
X1235594Y-57490D01*
X1234284Y-58365D01*
X1233411Y-60407D01*
X1232974Y-62157D01*
Y-63907D01*
X1233411Y-65657D01*
X1234503Y-67407D01*
X1235813Y-68573D01*
X1237341Y-68865D01*
X1238869Y-68282D01*
X1240398Y-66532D01*
G01X511800Y12507D02*
Y11707D01*
X510600Y10507D01*
X503514D01*
X499321Y14700D01*
X498121D01*
X496921Y13500D01*
X495721D01*
X494521Y14700D01*
X493321D01*
X492121Y13500D01*
X490921D01*
X489721Y14700D01*
X488521D01*
X487321Y13500D01*
X486121D01*
X484921Y14700D01*
X483721D01*
X482521Y13500D01*
X475300D01*
X474700Y14100D01*
Y16397D01*
X473997Y17100D01*
X473003D01*
X472300Y16397D01*
Y14100D01*
X471700Y13500D01*
X450700D01*
X450100Y14100D01*
Y16300D01*
X450700Y16900D01*
X454200D01*
X454800Y17500D01*
Y23900D01*
X454200Y24500D01*
X450600D01*
X449400Y23300D01*
X447800D01*
X446600Y24500D01*
X439500D01*
X438900Y25100D01*
Y34400D01*
X415936Y57364D01*
X381224D01*
X354271Y84317D01*
G01X370094Y75000D02*
X383130Y61964D01*
X417842D01*
X450496Y29310D01*
X458340D01*
X459400Y28250D01*
Y22700D01*
X460200Y21900D01*
X463543D01*
X464143Y22500D01*
Y23400D01*
X464743Y24000D01*
X465943D01*
X466543Y23400D01*
Y22500D01*
X467143Y21900D01*
X468343D01*
X468943Y22500D01*
Y23400D01*
X469543Y24000D01*
X470743D01*
X471343Y23400D01*
Y22500D01*
X471943Y21900D01*
X473143D01*
X473743Y22500D01*
Y23400D01*
X474343Y24000D01*
X475543D01*
X476143Y23400D01*
Y22500D01*
X476743Y21900D01*
X477943D01*
X478543Y22500D01*
Y23400D01*
X479143Y24000D01*
X480343D01*
X480943Y23400D01*
Y22500D01*
X481543Y21900D01*
X488800D01*
X489600Y22700D01*
Y27900D01*
X490500Y28800D01*
X501200D01*
X503500Y26500D01*
Y22500D01*
X504100Y21900D01*
X511400D01*
X512000Y22500D01*
Y24100D01*
X511400Y24700D01*
X510100D01*
X509500Y25300D01*
Y26700D01*
X510100Y27300D01*
X510989D01*
X511589Y27900D01*
Y30295D01*
G01X508700Y14607D02*
X507400D01*
X506800Y15207D01*
Y18600D01*
X506200Y19200D01*
X505000D01*
X504400Y18600D01*
Y15800D01*
X503800Y15200D01*
X502500D01*
X501900Y15800D01*
Y16800D01*
X501300Y17400D01*
X496600D01*
X495500Y18500D01*
X494000D01*
X492900Y17400D01*
X490943D01*
X490343Y18000D01*
Y19000D01*
X489743Y19600D01*
X488543D01*
X487943Y19000D01*
Y17700D01*
X487343Y17100D01*
X483699D01*
X483099Y17700D01*
Y19000D01*
X482499Y19600D01*
X480900D01*
X480300Y19000D01*
Y16400D01*
X479700Y15800D01*
X477799D01*
X477199Y16400D01*
Y18700D01*
X476399Y19500D01*
X470500D01*
X469900Y18900D01*
Y16300D01*
X469400Y15800D01*
X468000D01*
X467500Y16300D01*
Y18901D01*
X466900Y19501D01*
X465500D01*
X464900Y18901D01*
Y16400D01*
X464300Y15800D01*
X462900D01*
X462300Y16400D01*
Y18900D01*
X461700Y19500D01*
X460400D01*
X459800Y18900D01*
Y16650D01*
X459200Y16050D01*
X457700D01*
X457100Y16650D01*
Y26210D01*
X456300Y27010D01*
X449543D01*
X416889Y59664D01*
X382177D01*
X367370Y74471D01*
G01X507839Y30362D02*
Y28400D01*
X507239Y27800D01*
X505600D01*
X505000Y28400D01*
Y30500D01*
X504263Y31237D01*
X491763D01*
X491000Y32000D01*
X487800D01*
X487200Y31400D01*
Y24900D01*
X486600Y24300D01*
X485200D01*
X484600Y24900D01*
Y31400D01*
X484000Y32000D01*
X482600D01*
X482000Y31400D01*
Y27100D01*
X481200Y26300D01*
X473400D01*
X472600Y27100D01*
Y31000D01*
X472000Y31600D01*
X469500D01*
X468900Y31000D01*
Y26900D01*
X468300Y26300D01*
X467100D01*
X466500Y26900D01*
Y31010D01*
X465900Y31610D01*
X464700D01*
X464100Y31010D01*
Y26700D01*
X463500Y26100D01*
X462300D01*
X461700Y26700D01*
Y31010D01*
X461100Y31610D01*
X451449D01*
X418795Y64264D01*
X384083D01*
X370547Y77800D01*
G01X368600Y97500D02*
Y103400D01*
X369200Y104000D01*
X372500D01*
X373100Y103400D01*
Y100000D01*
X373700Y99400D01*
X383400D01*
X385300Y97500D01*
Y79400D01*
X385900Y78800D01*
X393199D01*
X395999Y76000D01*
X424880D01*
X448280Y52600D01*
X465100D01*
X465900Y51800D01*
Y45800D01*
X466700Y45000D01*
X469100D01*
X469900Y45800D01*
Y51800D01*
X470700Y52600D01*
X484781D01*
X485381Y52000D01*
Y50900D01*
X485981Y50300D01*
X487181D01*
X487781Y50900D01*
Y52000D01*
X488381Y52600D01*
X490100D01*
X490700Y52000D01*
Y51200D01*
X491300Y50600D01*
X493081D01*
X493681Y51200D01*
Y52000D01*
X494281Y52600D01*
X515700D01*
X526300Y42000D01*
Y35141D01*
X525028Y33869D01*
Y31618D01*
X525753Y30893D01*
G01X522733Y32832D02*
Y35033D01*
X524000Y36300D01*
Y41046D01*
X521721Y43323D01*
X520873D01*
X519848Y42298D01*
X519000D01*
X518151Y43148D01*
Y43996D01*
X519454Y45298D01*
Y46146D01*
X518604Y46996D01*
X517756D01*
X516930Y46170D01*
X514644D01*
X514044Y46770D01*
Y49700D01*
X513444Y50300D01*
X511400D01*
X510800Y49700D01*
Y46770D01*
X510200Y46170D01*
X507900D01*
X506070Y48000D01*
X485000D01*
X482700Y50300D01*
X473300D01*
X472500Y49500D01*
Y43300D01*
X471700Y42500D01*
X463700D01*
X462900Y43300D01*
Y49500D01*
X462100Y50300D01*
X453936D01*
X453336Y49700D01*
Y47503D01*
X452633Y46800D01*
X451639D01*
X450936Y47503D01*
Y49700D01*
X450336Y50300D01*
X447327D01*
X423627Y74000D01*
X394900D01*
X392000Y76900D01*
X384700D01*
X381400Y80200D01*
Y96400D01*
X380500Y97300D01*
X371300D01*
X370700Y96700D01*
Y93800D01*
G01X369450Y212040D02*
Y212080D01*
X367900Y213630D01*
Y222100D01*
X365100Y224900D01*
Y254749D01*
X378466Y268115D01*
X386800D01*
X389485Y270800D01*
X468700D01*
X471098Y273198D01*
X500002D01*
X502100Y271100D01*
Y264715D01*
X502915Y263900D01*
X506200D01*
X507900Y262200D01*
Y259696D01*
X511640Y255956D01*
G01X369580Y218800D02*
Y223222D01*
X367400Y225402D01*
Y245801D01*
X378601Y257002D01*
X379449D01*
X380538Y255913D01*
X381386D01*
X382236Y256763D01*
Y257611D01*
X381147Y258700D01*
Y259548D01*
X381997Y260398D01*
X382845D01*
X383934Y259309D01*
X384782D01*
X389100Y263627D01*
Y265788D01*
X390212Y266900D01*
X392873D01*
X394473Y268500D01*
X475794D01*
X476394Y269100D01*
Y269900D01*
X476994Y270500D01*
X478194D01*
X478794Y269900D01*
Y269100D01*
X479394Y268500D01*
X480594D01*
X481194Y269100D01*
Y269900D01*
X481794Y270500D01*
X482994D01*
X483594Y269900D01*
Y269100D01*
X484194Y268500D01*
X486494D01*
X488892Y270898D01*
X497702D01*
X499900Y268700D01*
Y265362D01*
X510956Y254306D01*
X512354D01*
X514137Y256089D01*
G01X376163Y80800D02*
X386999Y69964D01*
X421157D01*
X449021Y42100D01*
X450953D01*
X455253Y37800D01*
X485100D01*
X485700Y38400D01*
Y42800D01*
X486300Y43400D01*
X489000D01*
X490300Y42100D01*
X492800D01*
X494100Y43400D01*
X496100D01*
X497400Y42100D01*
X499700D01*
X501000Y43400D01*
X503000D01*
X504400Y42000D01*
X513300D01*
X517700Y37600D01*
Y29073D01*
X521273Y25500D01*
Y19607D01*
X520473Y18807D01*
X511400D01*
X510800Y18207D01*
Y15007D01*
X511400Y14407D01*
X515000D01*
X516900Y16307D01*
X519700D01*
X520700Y15307D01*
Y14807D01*
G01X373632Y78522D02*
X385590Y66564D01*
X419748D01*
X447612Y38700D01*
X449544D01*
X450722Y37522D01*
Y36578D01*
X451700Y35600D01*
X452644D01*
X453844Y34400D01*
X459775D01*
X460265Y33910D01*
X462065D01*
X462555Y34400D01*
X464355D01*
X464845Y33910D01*
X466645D01*
X467135Y34400D01*
X468935D01*
X469425Y33910D01*
X471225D01*
X471715Y34400D01*
X474400D01*
X475000Y33800D01*
Y30844D01*
X476244Y29600D01*
X478356D01*
X479600Y30844D01*
Y33800D01*
X480200Y34400D01*
X487871D01*
X489115Y35644D01*
Y37900D01*
X489715Y38500D01*
X491015D01*
X491615Y37900D01*
Y34844D01*
X492859Y33600D01*
X495056D01*
X496300Y34844D01*
Y37800D01*
X496800Y38300D01*
X498100D01*
X498700Y37700D01*
Y34744D01*
X499907Y33537D01*
X502056D01*
X503300Y34781D01*
Y38400D01*
X503600Y38700D01*
X504400D01*
X504890Y38210D01*
X506690D01*
X507180Y38700D01*
X512044D01*
X514655Y36089D01*
Y27045D01*
X516576Y25124D01*
Y23999D01*
X515484Y22907D01*
G01X518769D02*
X517676Y24000D01*
Y25580D01*
X515755Y27501D01*
Y36545D01*
X512500Y39800D01*
X503144D01*
X502200Y38856D01*
Y35237D01*
X501600Y34637D01*
X500363D01*
X499800Y35200D01*
Y38156D01*
X498556Y39400D01*
X496344D01*
X495200Y38256D01*
Y35300D01*
X494600Y34700D01*
X493315D01*
X492715Y35300D01*
Y38356D01*
X491471Y39600D01*
X489259D01*
X488015Y38356D01*
Y36100D01*
X487415Y35500D01*
X479744D01*
X478500Y34256D01*
Y31300D01*
X477900Y30700D01*
X476700D01*
X476100Y31300D01*
Y34256D01*
X474856Y35500D01*
X454300D01*
X450000Y39800D01*
X448068D01*
X420204Y67664D01*
X386046D01*
X374410Y79300D01*
G01X523453Y12360D02*
X523700Y12607D01*
Y15775D01*
X524932Y17007D01*
X527900D01*
X528500Y17607D01*
Y19317D01*
X527900Y19917D01*
X524100D01*
X523500Y20517D01*
Y22807D01*
X524100Y23407D01*
X527900D01*
X528500Y24007D01*
Y26507D01*
X527900Y27107D01*
X522700D01*
X520500Y29307D01*
Y31907D01*
X521083Y32490D01*
Y34017D01*
X520200Y34900D01*
Y38200D01*
X514600Y43800D01*
X505953D01*
X504053Y45700D01*
X483900D01*
X483300Y45100D01*
Y40800D01*
X482700Y40200D01*
X456106D01*
X451906Y44400D01*
X449974D01*
X422110Y72264D01*
X393382D01*
X392036Y73610D01*
Y73611D01*
X390747Y74900D01*
X384400D01*
X380400Y78900D01*
G01X376300Y211000D02*
X374600Y212700D01*
Y230700D01*
X379588Y235688D01*
Y243856D01*
X396732Y261000D01*
X406616D01*
X407106Y261490D01*
X408906D01*
X409396Y261000D01*
X411196D01*
X411686Y261490D01*
X413486D01*
X413976Y261000D01*
X415776D01*
X416266Y261490D01*
X418066D01*
X418556Y261000D01*
X422508D01*
X422998Y261490D01*
X424798D01*
X425288Y261000D01*
X430015D01*
X430505Y261490D01*
X432305D01*
X432795Y261000D01*
X434595D01*
X435085Y261490D01*
X436885D01*
X437375Y261000D01*
X439175D01*
X439665Y261490D01*
X441465D01*
X441955Y261000D01*
X443755D01*
X444245Y261490D01*
X446045D01*
X446535Y261000D01*
X448335D01*
X448825Y261490D01*
X450625D01*
X451115Y261000D01*
X452915D01*
X453405Y261490D01*
X455205D01*
X455695Y261000D01*
X458800D01*
X460887Y258913D01*
X489587D01*
X491300Y257200D01*
X494100D01*
X497000Y260100D01*
X499500D01*
X505300Y254300D01*
Y251500D01*
X506300Y250500D01*
X517900D01*
X518900Y251500D01*
Y255656D01*
X520400Y257156D01*
Y258344D01*
X518900Y259844D01*
Y261435D01*
X517846Y262489D01*
G01X385950Y229750D02*
X387500Y228200D01*
Y212800D01*
X386100Y211400D01*
X385789D01*
G01X385950Y229750D02*
X385250D01*
X384300Y228800D01*
Y212889D01*
X385789Y211400D01*
G01X376300Y216200D02*
X375700Y216800D01*
Y230244D01*
X380688Y235232D01*
Y243400D01*
X397188Y259900D01*
X458344D01*
X460431Y257813D01*
X489131D01*
X490844Y256100D01*
X494556D01*
X497456Y259000D01*
X499044D01*
X504200Y253844D01*
Y251044D01*
X505844Y249400D01*
X518356D01*
X520000Y251044D01*
Y255200D01*
X521500Y256700D01*
Y258800D01*
X520000Y260300D01*
Y261358D01*
X521131Y262489D01*
G01X511736Y273001D02*
Y272853D01*
X511737Y272852D01*
Y263095D01*
X515303Y259529D01*
X515837Y258994D01*
Y255337D01*
X513310Y252810D01*
X511037D01*
X495249Y268598D01*
X489845D01*
X485247Y264000D01*
X469000D01*
X466800Y266200D01*
X395426D01*
X374988Y245762D01*
Y235288D01*
G01X526715Y254700D02*
Y254581D01*
X525750Y253616D01*
Y251416D01*
X527025Y250141D01*
Y247900D01*
X526425Y247300D01*
X525400D01*
X524800Y247900D01*
Y249800D01*
X524200Y250400D01*
X523100D01*
X522500Y249800D01*
Y247700D01*
X521600Y246800D01*
X500000D01*
X499100Y247700D01*
Y250900D01*
X498500Y251500D01*
X495600D01*
X494700Y250600D01*
X485500D01*
X484900Y251200D01*
Y252613D01*
X484300Y253213D01*
X483009D01*
X482409Y252613D01*
Y251200D01*
X481809Y250600D01*
X480609D01*
X480009Y251200D01*
Y252613D01*
X479409Y253213D01*
X478209D01*
X477609Y252613D01*
Y251200D01*
X477009Y250600D01*
X475809D01*
X475209Y251200D01*
Y252613D01*
X474609Y253213D01*
X462406D01*
X461806Y252613D01*
Y251500D01*
X461206Y250900D01*
X460006D01*
X459406Y251500D01*
Y252613D01*
X458806Y253213D01*
X457606D01*
X457006Y252613D01*
Y251700D01*
X456406Y251100D01*
X455206D01*
X454606Y251700D01*
Y252613D01*
X454006Y253213D01*
X452806D01*
X452206Y252613D01*
Y251200D01*
X451606Y250600D01*
X450406D01*
X449806Y251200D01*
Y252613D01*
X449206Y253213D01*
X415119D01*
X413533Y251627D01*
X410627D01*
X409254Y253000D01*
X396794D01*
X385288Y241494D01*
Y235988D01*
G01X522908Y255117D02*
X523450Y254575D01*
Y252165D01*
X519385Y248100D01*
X504800D01*
X499100Y253800D01*
X489800D01*
X488087Y255513D01*
X445597D01*
X444997Y256113D01*
Y257000D01*
X444397Y257600D01*
X443197D01*
X442597Y257000D01*
Y256113D01*
X441997Y255513D01*
X440797D01*
X440197Y256113D01*
Y257000D01*
X439597Y257600D01*
X438397D01*
X437797Y257000D01*
Y256113D01*
X437197Y255513D01*
X435997D01*
X435397Y256113D01*
Y257000D01*
X434797Y257600D01*
X433597D01*
X432997Y257000D01*
Y256113D01*
X432397Y255513D01*
X431197D01*
X430597Y256113D01*
Y257000D01*
X429997Y257600D01*
X428797D01*
X428197Y257000D01*
Y256113D01*
X427597Y255513D01*
X416587D01*
X415200Y256900D01*
X414000D01*
X412400Y255300D01*
X411341D01*
X410741Y255900D01*
Y257000D01*
X410141Y257600D01*
X408941D01*
X408341Y257000D01*
Y255900D01*
X407741Y255300D01*
X406541D01*
X405941Y255900D01*
Y257000D01*
X405341Y257600D01*
X404141D01*
X403541Y257000D01*
Y255900D01*
X402941Y255300D01*
X401741D01*
X401141Y255900D01*
Y257000D01*
X400541Y257600D01*
X399341D01*
X398741Y257000D01*
Y255900D01*
X398141Y255300D01*
X395841D01*
X382988Y242447D01*
Y235888D01*
G01X514900Y271350D02*
X514237Y270687D01*
Y263563D01*
X517100Y260700D01*
Y255034D01*
X513876Y251810D01*
X510620D01*
X496132Y266298D01*
X490798D01*
X487347Y262847D01*
Y262846D01*
X486001Y261500D01*
X486000D01*
X485900Y261400D01*
X462000D01*
X459500Y263900D01*
X396379D01*
X377288Y244809D01*
Y235788D01*
G01X588036Y273089D02*
X585689D01*
X584700Y272100D01*
Y269400D01*
X583900Y268600D01*
X576186D01*
X575600Y268014D01*
Y267200D01*
X576200Y266600D01*
X578800D01*
X579400Y266000D01*
Y258100D01*
X578800Y257500D01*
X576500D01*
X575900Y258100D01*
Y259700D01*
X575300Y260300D01*
X573563D01*
X572963Y259700D01*
Y258100D01*
X572363Y257500D01*
X570837D01*
X570237Y258100D01*
Y263700D01*
X569637Y264300D01*
X568437D01*
X567837Y263700D01*
Y258300D01*
X567237Y257700D01*
X566037D01*
X565437Y258300D01*
Y263900D01*
X564837Y264500D01*
X563637D01*
X563037Y263900D01*
Y260037D01*
X562100Y259100D01*
X559200D01*
X556100Y256000D01*
Y252200D01*
X554200Y250300D01*
X549500D01*
X535700Y236500D01*
X512454D01*
X511829Y235875D01*
X403875D01*
X393800Y225800D01*
G01X591536Y273000D02*
Y273864D01*
X590610Y274790D01*
X574950D01*
X574350Y274190D01*
Y269900D01*
X573750Y269300D01*
X572300D01*
X571700Y268700D01*
Y268000D01*
X571100Y267400D01*
X569853D01*
X568753Y268500D01*
X565074D01*
X562037Y265463D01*
Y262937D01*
X559889Y260789D01*
X558221D01*
X558210Y260800D01*
X557200D01*
X554000Y257600D01*
X551400D01*
X550800Y258200D01*
Y259200D01*
X553276Y261676D01*
Y262524D01*
X552124Y263676D01*
X551276D01*
X547500Y259900D01*
Y251200D01*
X535100Y238800D01*
X471300D01*
X470675Y238175D01*
X403475D01*
X391800Y226500D01*
G01X402524Y225500D02*
Y229324D01*
X404475Y231275D01*
X475584D01*
X476559Y230300D01*
X478859D01*
X479834Y231275D01*
X481259D01*
X482234Y230300D01*
X483659D01*
X484634Y231275D01*
X486059D01*
X487034Y230300D01*
X488459D01*
X489434Y231275D01*
X490859D01*
X491834Y230300D01*
X493259D01*
X494234Y231275D01*
X495659D01*
X496634Y230300D01*
X498059D01*
X499034Y231275D01*
X500459D01*
X501434Y230300D01*
X502859D01*
X503834Y231275D01*
X505259D01*
X506234Y230300D01*
X537676D01*
X538276Y230900D01*
Y231700D01*
X538876Y232300D01*
X540200D01*
X541400Y231100D01*
X542047D01*
X544947Y234000D01*
Y235295D01*
X543673Y236569D01*
Y237417D01*
X544523Y238267D01*
X545371D01*
X546895Y236743D01*
X547743D01*
X548593Y237593D01*
Y238441D01*
X547069Y239965D01*
Y240813D01*
X547919Y241663D01*
X548767D01*
X550041Y240389D01*
X550889D01*
X551739Y241239D01*
Y242087D01*
X550465Y243361D01*
Y244209D01*
X551315Y245059D01*
X552163D01*
X553437Y243785D01*
X556700D01*
X557300Y244385D01*
Y247200D01*
X557900Y247800D01*
X559754D01*
X560354Y247200D01*
Y244400D01*
X560954Y243800D01*
X562154D01*
X562754Y244400D01*
Y247200D01*
X563354Y247800D01*
X564554D01*
X565154Y247200D01*
Y244300D01*
X565754Y243700D01*
X566954D01*
X567554Y244300D01*
Y247200D01*
X568154Y247800D01*
X569354D01*
X569954Y247200D01*
Y244300D01*
X570554Y243700D01*
X571754D01*
X572354Y244300D01*
Y247200D01*
X572954Y247800D01*
X574154D01*
X574754Y247200D01*
Y244600D01*
X575354Y244000D01*
X576554D01*
X577154Y244600D01*
Y247000D01*
X577754Y247600D01*
X583036D01*
X587642Y252206D01*
G01X587700Y255300D02*
Y264200D01*
X586900Y265000D01*
X582000D01*
X581400Y264400D01*
Y263200D01*
X582000Y262600D01*
X584500D01*
X585100Y262000D01*
Y260800D01*
X584500Y260200D01*
X582000D01*
X581400Y259600D01*
Y258400D01*
X582000Y257800D01*
X583900D01*
X584500Y257200D01*
Y251610D01*
X582790Y249900D01*
X577500D01*
X576900Y250500D01*
Y252800D01*
X576300Y253400D01*
X574443D01*
X573843Y252800D01*
Y250500D01*
X573243Y249900D01*
X556000D01*
X553400Y247300D01*
X550300D01*
X535600Y232600D01*
X532686D01*
X532086Y233200D01*
Y233900D01*
X531486Y234500D01*
X530286D01*
X529686Y233900D01*
Y233200D01*
X529086Y232600D01*
X527886D01*
X527286Y233200D01*
Y233900D01*
X526686Y234500D01*
X525486D01*
X524886Y233900D01*
Y233200D01*
X524286Y232600D01*
X523086D01*
X522486Y233200D01*
Y233900D01*
X521886Y234500D01*
X520686D01*
X520086Y233900D01*
Y233200D01*
X519486Y232600D01*
X510975D01*
X510000Y233575D01*
X404175D01*
X397800Y227200D01*
Y216600D01*
G01X389888Y236138D02*
Y239588D01*
X398700Y248400D01*
X407347D01*
X408720Y247027D01*
X415439D01*
X417012Y248600D01*
X444700D01*
X447400Y245900D01*
X464847D01*
X467560Y248613D01*
X469800D01*
X474313Y244100D01*
X529534D01*
X537450Y252016D01*
Y254750D01*
X526137Y266063D01*
Y269200D01*
X525400Y269937D01*
Y272418D01*
X525845Y272863D01*
G01X522992Y270700D02*
X524800Y268892D01*
Y259100D01*
X528365Y255535D01*
Y254235D01*
X529050Y253550D01*
Y247750D01*
X526800Y245500D01*
X496854D01*
X494054Y248300D01*
X473366D01*
X470753Y250913D01*
X466607D01*
X463894Y248200D01*
X448353D01*
X445640Y250913D01*
X416072D01*
X414486Y249327D01*
X409674D01*
X408301Y250700D01*
X397747D01*
X387588Y240541D01*
Y236088D01*
G01X406375Y210825D02*
X410300Y214750D01*
Y225800D01*
X411300Y226800D01*
X424881D01*
X425006Y226675D01*
X471713D01*
X476088Y222300D01*
X492806D01*
X493406Y222900D01*
Y225100D01*
X494006Y225700D01*
X495206D01*
X495806Y225100D01*
Y222900D01*
X496406Y222300D01*
X497606D01*
X498206Y222900D01*
Y225100D01*
X498806Y225700D01*
X500006D01*
X500606Y225100D01*
Y222900D01*
X501206Y222300D01*
X502406D01*
X503006Y222900D01*
Y225100D01*
X503606Y225700D01*
X504806D01*
X505406Y225100D01*
Y222900D01*
X506006Y222300D01*
X507206D01*
X507806Y222900D01*
Y225100D01*
X508406Y225700D01*
X509606D01*
X510206Y225100D01*
Y222900D01*
X510806Y222300D01*
X512006D01*
X512606Y222900D01*
Y225100D01*
X513206Y225700D01*
X514406D01*
X515006Y225100D01*
Y222900D01*
X515606Y222300D01*
X516806D01*
X517406Y222900D01*
Y225100D01*
X518006Y225700D01*
X519206D01*
X519806Y225100D01*
Y222900D01*
X520406Y222300D01*
X522100D01*
X523900Y224100D01*
X524600D01*
X526400Y222300D01*
X528359D01*
X529759Y223700D01*
X533241D01*
X534741Y222200D01*
X539653D01*
X543180Y225727D01*
X544028D01*
X546703Y223051D01*
X547551D01*
X548401Y223901D01*
Y224749D01*
X545726Y227425D01*
Y228273D01*
X546576Y229123D01*
X547424D01*
X550099Y226447D01*
X550947D01*
X551797Y227297D01*
Y228145D01*
X549122Y230821D01*
Y231669D01*
X550953Y233500D01*
X553897D01*
X554497Y232900D01*
Y231300D01*
X555097Y230700D01*
X556297D01*
X556897Y231300D01*
Y234000D01*
X557497Y234600D01*
X575835D01*
X591342Y250107D01*
Y252206D01*
G01X591300Y255010D02*
X589442Y253152D01*
Y251460D01*
X579782Y241800D01*
X574100D01*
X573500Y241200D01*
Y236800D01*
X572900Y236200D01*
X571700D01*
X571100Y236800D01*
Y241200D01*
X570500Y241800D01*
X569300D01*
X568700Y241200D01*
Y236800D01*
X568100Y236200D01*
X566900D01*
X566300Y236800D01*
Y241200D01*
X565700Y241800D01*
X562700D01*
X561600Y240700D01*
Y237300D01*
X561000Y236700D01*
X560100D01*
X559500Y237300D01*
Y241000D01*
X558700Y241800D01*
X556000D01*
X554041Y239841D01*
Y238993D01*
X555243Y237791D01*
Y236943D01*
X554393Y236093D01*
X553545D01*
X552343Y237295D01*
X551495D01*
X538900Y224700D01*
X537000D01*
X536525Y225175D01*
Y227400D01*
X535925Y228000D01*
X534300D01*
X533800Y227500D01*
Y227000D01*
X532800Y226000D01*
X529753D01*
X527753Y228000D01*
X491106D01*
X490506Y227400D01*
Y225200D01*
X489906Y224600D01*
X488706D01*
X488106Y225200D01*
Y227400D01*
X487506Y228000D01*
X486306D01*
X485706Y227400D01*
Y225200D01*
X485106Y224600D01*
X483906D01*
X483306Y225200D01*
Y227400D01*
X482706Y228000D01*
X481506D01*
X480906Y227400D01*
Y225200D01*
X480306Y224600D01*
X479106D01*
X478506Y225200D01*
Y227400D01*
X477906Y228000D01*
X475606D01*
X474631Y228975D01*
X407675D01*
X406200Y227500D01*
Y213100D01*
X404000Y210900D01*
G01X588400Y270300D02*
X587000D01*
X586400Y269700D01*
Y267700D01*
X587617Y266483D01*
X591854D01*
X592537Y265800D01*
Y259653D01*
X593142Y259048D01*
Y248654D01*
X575688Y231200D01*
X573753D01*
X573752Y231201D01*
X571848D01*
X571847Y231200D01*
X571200D01*
X570600Y230600D01*
Y229000D01*
X570000Y228400D01*
X568300D01*
X567700Y229000D01*
Y231700D01*
X567100Y232300D01*
X565800D01*
X565200Y231700D01*
Y229100D01*
X564600Y228500D01*
X563200D01*
X562600Y229100D01*
Y231700D01*
X562000Y232300D01*
X559797D01*
X559197Y231700D01*
Y227984D01*
X556735Y225522D01*
X555888D01*
X555029Y226381D01*
X554181D01*
X553331Y225531D01*
Y224683D01*
X554189Y223824D01*
Y222976D01*
X551113Y219900D01*
X546601D01*
X544504Y221997D01*
X542703D01*
X540606Y219900D01*
X533788D01*
X532288Y221400D01*
X530712D01*
X529312Y220000D01*
X502447D01*
X500747Y218300D01*
X497000D01*
X495300Y220000D01*
X492000D01*
X491190Y219190D01*
X486910D01*
X486100Y220000D01*
X483273D01*
X481573Y218300D01*
X476835D01*
X470760Y224375D01*
X425006D01*
X424781Y224600D01*
X415000D01*
X413800Y223400D01*
Y221000D01*
X414100Y220700D01*
Y216500D01*
X408425Y210825D01*
G01X591500Y270100D02*
X592300D01*
X593400Y271200D01*
Y274300D01*
X594000Y274900D01*
X600200D01*
X600800Y274300D01*
Y267900D01*
X600100Y267200D01*
X597100D01*
X596287Y266387D01*
Y259303D01*
X595000Y258016D01*
Y247259D01*
X576641Y228900D01*
X574200D01*
X571200Y225900D01*
X563412D01*
X562412Y224900D01*
X559366D01*
X551966Y217500D01*
X503200D01*
X501700Y216000D01*
X495632D01*
X494742Y216890D01*
X483416D01*
X482526Y216000D01*
X475882D01*
X469807Y222075D01*
X426925D01*
X425600Y220750D01*
X418450D01*
X417650Y219950D01*
Y214550D01*
X416950Y213850D01*
G01X730400Y255400D02*
Y254500D01*
X725400Y249500D01*
X701600D01*
X697271Y245171D01*
X696423D01*
X695721Y245873D01*
X694873D01*
X694023Y245023D01*
Y244175D01*
X694725Y243473D01*
Y242625D01*
X693875Y241775D01*
X693027D01*
X692325Y242477D01*
X691477D01*
X690627Y241627D01*
Y240779D01*
X691329Y240077D01*
Y239229D01*
X690479Y238379D01*
X689631D01*
X688929Y239081D01*
X688081D01*
X687231Y238231D01*
Y237383D01*
X687933Y236681D01*
Y235833D01*
X687083Y234983D01*
X686235D01*
X685533Y235685D01*
X684685D01*
X683835Y234835D01*
Y233987D01*
X684537Y233285D01*
Y232437D01*
X683687Y231587D01*
X682839D01*
X682137Y232289D01*
X681289D01*
X680439Y231439D01*
Y230591D01*
X681141Y229889D01*
Y229041D01*
X680291Y228191D01*
X679443D01*
X678741Y228893D01*
X677893D01*
X677043Y228043D01*
Y227195D01*
X677745Y226493D01*
Y225645D01*
X676895Y224795D01*
X676047D01*
X675345Y225497D01*
X674497D01*
X673647Y224647D01*
Y223799D01*
X674349Y223097D01*
Y222249D01*
X673499Y221399D01*
X672651D01*
X671949Y222101D01*
X671101D01*
X670251Y221251D01*
Y220403D01*
X670953Y219701D01*
Y218853D01*
X667965Y215865D01*
X656765D01*
X653053Y212153D01*
X652205D01*
X650553Y213805D01*
X649705D01*
X648855Y212955D01*
Y212107D01*
X650507Y210455D01*
Y209607D01*
X649657Y208757D01*
X648809D01*
X647157Y210409D01*
X646309D01*
X645459Y209559D01*
Y208711D01*
X647111Y207059D01*
Y206211D01*
X646261Y205361D01*
X645413D01*
X643761Y207013D01*
X642913D01*
X642063Y206163D01*
Y205315D01*
X643715Y203663D01*
Y202815D01*
X642865Y201965D01*
X642017D01*
X640365Y203617D01*
X639517D01*
X638667Y202767D01*
Y201919D01*
X640319Y200267D01*
Y199419D01*
X637200Y196300D01*
X624915D01*
X599702Y171087D01*
X461587D01*
X459700Y169200D01*
X434900D01*
X432383Y166683D01*
X431303D01*
X431280Y166660D01*
X431130D01*
G01X431220Y168600D02*
X433620Y171000D01*
X440500D01*
X442500Y173000D01*
X466000D01*
X466387Y173387D01*
X598749D01*
X625562Y200200D01*
X629835D01*
X647800Y218165D01*
X658624D01*
X661817Y221358D01*
X662665D01*
X663388Y220638D01*
X664238D01*
X665083Y221483D01*
Y222333D01*
X664363Y223056D01*
Y223904D01*
X665213Y224754D01*
X666061D01*
X666833Y223982D01*
X667680D01*
X668530Y224832D01*
Y225680D01*
X667759Y226452D01*
Y227300D01*
X668609Y228150D01*
X669457D01*
X670229Y227378D01*
X671076D01*
X671926Y228228D01*
Y229076D01*
X671155Y229848D01*
Y230696D01*
X672005Y231546D01*
X672853D01*
X673625Y230774D01*
X674472D01*
X675322Y231624D01*
Y232472D01*
X674551Y233244D01*
Y234092D01*
X675401Y234942D01*
X676249D01*
X677021Y234170D01*
X677868D01*
X678718Y235020D01*
Y235868D01*
X677947Y236640D01*
Y237488D01*
X678797Y238338D01*
X679645D01*
X680417Y237566D01*
X681264D01*
X682114Y238416D01*
Y239264D01*
X681343Y240036D01*
Y240884D01*
X682193Y241734D01*
X683041D01*
X683813Y240962D01*
X684660D01*
X685510Y241812D01*
Y242660D01*
X684739Y243432D01*
Y244280D01*
X687040Y246581D01*
Y256340D01*
X689900Y259200D01*
X725000D01*
X734570Y268770D01*
Y270716D01*
X732436Y272850D01*
X730400D01*
G01X732740Y270200D02*
X732700D01*
X730189Y267689D01*
X692389D01*
X679384Y254684D01*
Y247697D01*
X674946Y243259D01*
Y242411D01*
X676005Y241354D01*
Y240505D01*
X675155Y239654D01*
X674308D01*
X673248Y240713D01*
X672400D01*
X671550Y239863D01*
Y239015D01*
X672858Y237708D01*
Y236860D01*
X672008Y236010D01*
X671160D01*
X669852Y237317D01*
X669004D01*
X668154Y236467D01*
Y235619D01*
X669462Y234312D01*
Y233464D01*
X668612Y232614D01*
X667764D01*
X666456Y233921D01*
X665608D01*
X664758Y233071D01*
Y232223D01*
X666066Y230916D01*
Y230068D01*
X665216Y229218D01*
X664368D01*
X663060Y230525D01*
X662212D01*
X661362Y229675D01*
Y228827D01*
X662670Y227520D01*
Y226672D01*
X661820Y225822D01*
X660972D01*
X659664Y227129D01*
X658816D01*
X656887Y225200D01*
X651582D01*
X628882Y202500D01*
X624609D01*
X597796Y175687D01*
X463313D01*
X461900Y177100D01*
X442600D01*
X440500Y175000D01*
X429370D01*
X429310Y174940D01*
G01X637337Y272944D02*
X637856D01*
X641703Y269097D01*
Y267327D01*
X646583Y262447D01*
Y261317D01*
X650000Y257900D01*
Y237522D01*
X597981Y185503D01*
X493434D01*
X491531Y183600D01*
X443000D01*
X433175Y193425D01*
X431270D01*
G01X735168Y262489D02*
X736260Y261397D01*
Y256784D01*
X737000Y256044D01*
Y252726D01*
X735269Y250995D01*
X733927Y249945D01*
X733926D01*
X733095Y249294D01*
X733091Y249291D01*
X731563Y248094D01*
X727364Y245700D01*
X717744D01*
X716471Y244427D01*
X715778D01*
X714505Y243154D01*
Y242461D01*
X713233Y241189D01*
X712540D01*
X711267Y239916D01*
Y239223D01*
X706144Y234100D01*
X701588D01*
X700233Y232745D01*
X699540D01*
X698268Y231473D01*
Y230780D01*
X693388Y225900D01*
X690600D01*
X688608Y223908D01*
Y220964D01*
X685844Y218200D01*
X681591D01*
X680318Y216927D01*
X679625D01*
X678352Y215654D01*
Y214961D01*
X676601Y213210D01*
X675908D01*
X674635Y211937D01*
Y211244D01*
X673362Y209971D01*
X657377D01*
X654289Y206883D01*
Y205123D01*
X656782Y202630D01*
Y201782D01*
X655082Y200082D01*
X654234D01*
X651741Y202575D01*
X649981D01*
X639106Y191700D01*
X626821D01*
X601608Y166487D01*
X467831D01*
X465044Y163700D01*
X447456D01*
X445719Y165437D01*
X441480D01*
G01X741200Y270500D02*
X740500Y269800D01*
Y268237D01*
X742137Y266600D01*
Y264763D01*
X743100Y263800D01*
Y262063D01*
X742137Y261100D01*
Y259163D01*
X745733Y255567D01*
X746007Y254473D01*
X746137Y253952D01*
Y251484D01*
X744276Y249623D01*
X733400Y240900D01*
X674345Y197282D01*
X625224Y169864D01*
X615938Y164681D01*
X604839Y158486D01*
X604838Y158487D01*
X469587D01*
X468700Y157600D01*
X439813D01*
G01X434834Y163817D02*
X435261D01*
X438444Y167000D01*
X448000D01*
X449500Y165500D01*
X463000D01*
X466287Y168787D01*
X600655D01*
X625868Y194000D01*
X638153D01*
X656424Y212271D01*
X671471D01*
X673258Y214058D01*
Y214906D01*
X672256Y215908D01*
Y216756D01*
X673106Y217606D01*
X673954D01*
X674956Y216604D01*
X675804D01*
X676654Y217454D01*
Y218302D01*
X675652Y219304D01*
Y220152D01*
X676502Y221002D01*
X677350D01*
X678352Y220000D01*
X679200D01*
X680050Y220850D01*
Y221698D01*
X679048Y222700D01*
Y223548D01*
X679898Y224398D01*
X680746D01*
X681748Y223396D01*
X682596D01*
X683446Y224246D01*
Y225094D01*
X682444Y226096D01*
Y226944D01*
X683294Y227794D01*
X684142D01*
X685144Y226792D01*
X685992D01*
X686842Y227642D01*
Y228490D01*
X685840Y229492D01*
Y230340D01*
X686690Y231190D01*
X687538D01*
X688540Y230188D01*
X689388D01*
X691839Y232639D01*
X692687D01*
X693294Y232032D01*
X694142D01*
X694992Y232882D01*
Y233730D01*
X694385Y234337D01*
Y235185D01*
X695591Y236391D01*
X696439D01*
X697760Y235070D01*
X698608D01*
X699458Y235920D01*
Y236768D01*
X698137Y238089D01*
Y238937D01*
X698987Y239787D01*
X699835D01*
X702887Y236735D01*
X703735D01*
X704585Y237585D01*
Y238433D01*
X701533Y241485D01*
Y242333D01*
X702383Y243183D01*
X703231D01*
X706783Y239631D01*
X707631D01*
X708481Y240481D01*
Y241329D01*
X704929Y244881D01*
Y245729D01*
X706600Y247400D01*
X725800D01*
X728889Y250489D01*
X731137D01*
X732200Y251552D01*
Y252200D01*
G01X441200Y162737D02*
X444263D01*
X446100Y160900D01*
X466400D01*
X468587Y163087D01*
X603017D01*
X628230Y188300D01*
X640515D01*
X644640Y192425D01*
X645488D01*
X647033Y190880D01*
X647881D01*
X648731Y191730D01*
Y192578D01*
X647186Y194123D01*
Y194971D01*
X648815Y196600D01*
X657800D01*
X663470Y202270D01*
Y203118D01*
X662168Y204420D01*
Y205268D01*
X663018Y206118D01*
X663866D01*
X665168Y204816D01*
X666016D01*
X667700Y206500D01*
X674700D01*
X682400Y214200D01*
X687547D01*
X702747Y229400D01*
X706900D01*
X719407Y241907D01*
X727700D01*
X731842Y244657D01*
X731960D01*
X741248Y251216D01*
X742000Y251968D01*
Y254560D01*
X741560Y255000D01*
G01X744200Y272600D02*
X747076Y254987D01*
X747137Y254500D01*
Y251069D01*
X735968Y239900D01*
X675400Y195200D01*
X626180Y167613D01*
X605792Y156186D01*
X595683D01*
X595681Y156187D01*
X441700D01*
G01X744437Y252189D02*
X743837Y251589D01*
Y251484D01*
X743076Y250723D01*
X731800Y242400D01*
X728300Y239700D01*
X720600D01*
X717948Y237048D01*
Y236200D01*
X718550Y235598D01*
Y234750D01*
X717700Y233900D01*
X716852D01*
X716250Y234502D01*
X715402D01*
X714552Y233652D01*
Y232804D01*
X715154Y232202D01*
Y231354D01*
X714304Y230504D01*
X713456D01*
X712854Y231106D01*
X712006D01*
X703200Y222300D01*
X698900D01*
X695160Y218560D01*
Y216660D01*
X693610Y215110D01*
X691710D01*
X688273Y211673D01*
X683126D01*
X680261Y208808D01*
Y207960D01*
X680989Y207232D01*
Y206384D01*
X680139Y205534D01*
X679291D01*
X678563Y206262D01*
X677715D01*
X676865Y205412D01*
Y204564D01*
X677593Y203836D01*
Y202988D01*
X676743Y202138D01*
X675895D01*
X675167Y202866D01*
X674319D01*
X667653Y196200D01*
X667612Y196160D01*
X646605Y184500D01*
X627683D01*
X603970Y160787D01*
X469187D01*
X467800Y159400D01*
X445100D01*
X443300Y161200D01*
X440500D01*
G01X738453Y262489D02*
X737360Y261396D01*
Y257240D01*
X738100Y256500D01*
Y252270D01*
X736000Y250170D01*
X733774Y248427D01*
X733770Y248424D01*
X732178Y247178D01*
X727656Y244600D01*
X718200D01*
X706600Y233000D01*
X702044D01*
X693844Y224800D01*
X691056D01*
X689708Y223452D01*
Y220508D01*
X686300Y217100D01*
X682047D01*
X673818Y208871D01*
X657833D01*
X655389Y206427D01*
Y205579D01*
X657882Y203086D01*
Y201326D01*
X655538Y198982D01*
X653778D01*
X651285Y201475D01*
X650437D01*
X639562Y190600D01*
X627277D01*
X602064Y165387D01*
X468287D01*
X465500Y162600D01*
X447000D01*
X445263Y164337D01*
X441653D01*
G01X437921Y192956D02*
X443577Y187300D01*
X475800D01*
X476600Y186500D01*
X491178D01*
X492497Y187819D01*
X498395D01*
X499251Y188675D01*
X500795D01*
X501651Y187819D01*
X503195D01*
X504051Y188675D01*
X505595D01*
X506451Y187819D01*
X507995D01*
X508851Y188675D01*
X510395D01*
X511251Y187819D01*
X512795D01*
X513651Y188675D01*
X515195D01*
X516051Y187819D01*
X517595D01*
X518451Y188675D01*
X519995D01*
X520851Y187819D01*
X522395D01*
X523251Y188675D01*
X524795D01*
X525651Y187819D01*
X562388D01*
X563244Y188675D01*
X564788D01*
X565644Y187819D01*
X567188D01*
X568044Y188675D01*
X569588D01*
X570444Y187819D01*
X576788D01*
X577644Y188675D01*
X579188D01*
X580044Y187819D01*
X581588D01*
X582444Y188675D01*
X588058D01*
X595511Y196128D01*
X603030D01*
X603768Y195390D01*
X604615D01*
X605465Y196240D01*
Y197088D01*
X604728Y197826D01*
Y198674D01*
X605578Y199524D01*
X606426D01*
X607164Y198786D01*
X608011D01*
X639508Y230283D01*
Y231131D01*
X638194Y232446D01*
Y233294D01*
X639044Y234144D01*
X639892D01*
X641206Y232829D01*
X642054D01*
X642904Y233679D01*
Y234527D01*
X639390Y238043D01*
Y238890D01*
X640241Y239740D01*
X641089D01*
X644602Y236225D01*
X645450D01*
X647612Y238387D01*
Y244288D01*
X640693Y251207D01*
Y253307D01*
X639191Y254809D01*
X638900D01*
G01X635043Y252106D02*
Y245849D01*
X634200Y245006D01*
X632500D01*
X631900Y244406D01*
Y243206D01*
X632500Y242606D01*
X634700D01*
X635300Y242006D01*
Y240806D01*
X634700Y240206D01*
X632900D01*
X632300Y239606D01*
Y238406D01*
X632900Y237806D01*
X634600D01*
X635200Y237206D01*
Y236006D01*
X634600Y235406D01*
X633000D01*
X632400Y234806D01*
Y233606D01*
X633000Y233006D01*
X634443D01*
X635043Y232406D01*
Y229143D01*
X633076Y227176D01*
X632228D01*
X631176Y228228D01*
X630328D01*
X629478Y227378D01*
Y226530D01*
X630530Y225478D01*
Y224630D01*
X628901Y223001D01*
X628053D01*
X627101Y223953D01*
X626253D01*
X625403Y223103D01*
Y222255D01*
X626355Y221303D01*
Y220455D01*
X624726Y218826D01*
X623878D01*
X623486Y219218D01*
X622638D01*
X621788Y218368D01*
Y217520D01*
X622180Y217128D01*
Y216280D01*
X621330Y215430D01*
X620482D01*
X620090Y215822D01*
X619242D01*
X618392Y214972D01*
Y214124D01*
X618784Y213732D01*
Y212884D01*
X615407Y209507D01*
X614559D01*
X614107Y209959D01*
X613260D01*
X612410Y209109D01*
Y208261D01*
X612861Y207809D01*
Y206961D01*
X612011Y206111D01*
X611163D01*
X610711Y206563D01*
X609864D01*
X609014Y205713D01*
Y204865D01*
X609465Y204413D01*
Y203565D01*
X607724Y201824D01*
X604624D01*
X603100Y200300D01*
X596430D01*
X589205Y193075D01*
X567734D01*
X565634Y190975D01*
X559827D01*
X558971Y190119D01*
X557427D01*
X556571Y190975D01*
X555027D01*
X554171Y190119D01*
X552627D01*
X551771Y190975D01*
X550227D01*
X549371Y190119D01*
X547827D01*
X546971Y190975D01*
X545427D01*
X544571Y190119D01*
X543027D01*
X542171Y190975D01*
X540627D01*
X539771Y190119D01*
X538227D01*
X537371Y190975D01*
X535827D01*
X534971Y190119D01*
X533427D01*
X532571Y190975D01*
X531027D01*
X530171Y190119D01*
X528627D01*
X527771Y190975D01*
X496956D01*
X496100Y190119D01*
X494581D01*
X493725Y190975D01*
X491425D01*
X490825Y190375D01*
Y189400D01*
X490225Y188800D01*
X488425D01*
X487825Y189400D01*
Y190375D01*
X487225Y190975D01*
X485425D01*
X484825Y190375D01*
Y189400D01*
X484225Y188800D01*
X482425D01*
X481825Y189400D01*
Y190375D01*
X481225Y190975D01*
X479425D01*
X478825Y190375D01*
Y189400D01*
X478225Y188800D01*
X476425D01*
X475825Y189400D01*
Y190375D01*
X475225Y190975D01*
X442349D01*
X438500Y194824D01*
X435642D01*
G01X637288Y270100D02*
Y268378D01*
X638566Y267100D01*
X639400D01*
X642000Y264500D01*
Y260100D01*
X640000Y258100D01*
X632100D01*
X629400Y255400D01*
Y252615D01*
X628800Y252015D01*
X627300D01*
X626700Y251415D01*
Y250215D01*
X627300Y249615D01*
X628800D01*
X629400Y249015D01*
Y247815D01*
X628800Y247215D01*
X627300D01*
X626700Y246615D01*
Y245415D01*
X627300Y244815D01*
X628800D01*
X629400Y244215D01*
Y243015D01*
X628800Y242415D01*
X627300D01*
X626700Y241815D01*
Y240615D01*
X627300Y240015D01*
X628800D01*
X629400Y239415D01*
Y238215D01*
X628800Y237615D01*
X627300D01*
X626700Y237015D01*
Y235815D01*
X627300Y235215D01*
X628800D01*
X629400Y234615D01*
Y233415D01*
X628800Y232815D01*
X627300D01*
X626700Y232215D01*
Y227793D01*
X621984Y223077D01*
Y221818D01*
X618416Y218250D01*
X618415D01*
X613975Y213810D01*
X612717D01*
X609947Y211040D01*
Y209974D01*
X606186Y206213D01*
X605120D01*
X604203Y205296D01*
X598173D01*
X588252Y195375D01*
X566781D01*
X564681Y193275D01*
X466025D01*
X460500Y198800D01*
X440318D01*
X438742Y197224D01*
G54D12*
X276811Y263386D03*
X296811D03*
G54D22*
G01X787800Y179900D02*
X778829D01*
X777000Y178071D01*
Y128800D01*
X763500Y115300D01*
Y105153D01*
X762304Y103957D01*
G01X787600Y183300D02*
X786800Y182500D01*
X778600D01*
X775000Y178900D01*
Y129629D01*
X761500Y116129D01*
Y106834D01*
X758916Y104250D01*
G54D13*
X309000Y114700D03*
X306700D03*
X307298Y132697D03*
X309220Y153698D03*
X305800Y195400D03*
X303500D03*
X315950Y98650D03*
X320992Y112180D03*
X319096Y113300D03*
X323900Y129900D03*
X325418Y127349D03*
X325746Y133702D03*
X323500Y180063D03*
X316000Y237700D03*
X319100D03*
X336750Y93500D03*
Y95704D03*
X333313Y103693D03*
X333434Y106668D03*
X338329Y135665D03*
X335303Y135178D03*
X335450Y150900D03*
X330163Y142008D03*
X341342Y138224D03*
X339491Y143163D03*
X330821Y177402D03*
X329442Y169463D03*
X327708Y177241D03*
X332353Y169522D03*
X337000Y174102D03*
X327600Y174174D03*
X330027Y174119D03*
X337863Y180545D03*
X330280Y180900D03*
X332500D03*
X328510Y218320D03*
X327024Y220024D03*
X328945Y235846D03*
X331142Y233658D03*
X346596Y118163D03*
Y115163D03*
X351500Y136000D03*
X342533Y133822D03*
X357300Y128600D03*
X355400Y137100D03*
X354300Y128600D03*
X346300Y143000D03*
X355447Y146528D03*
X348675Y143326D03*
X348743Y146072D03*
X346000Y146043D03*
X342188Y183361D03*
X342233Y185639D03*
X349600Y194800D03*
X345500Y184500D03*
X345631Y187420D03*
X364800Y91200D03*
X368600Y90700D03*
X361200Y90200D03*
X364874Y98250D03*
X362803Y106035D03*
X357900Y99200D03*
X368600Y97500D03*
X357721Y91779D03*
X361200Y97500D03*
X365316Y108130D03*
X362111Y127142D03*
X362120Y124153D03*
X359421Y127128D03*
Y124008D03*
X359300Y130000D03*
X367900Y152550D03*
X368026Y149718D03*
X364600Y174800D03*
X361500Y175000D03*
X367906Y171458D03*
X364600Y171600D03*
X364607Y177103D03*
X370900Y171700D03*
X361200Y178500D03*
X372400Y179100D03*
X369021Y180128D03*
X372600Y181400D03*
X364895Y190941D03*
X369106Y191903D03*
X369200Y189100D03*
X361257Y193524D03*
Y190700D03*
X364947Y193141D03*
X372700Y213700D03*
X369450Y212040D03*
X358498Y210220D03*
X358382Y212427D03*
X372800Y221600D03*
X369580Y218800D03*
X386853Y149640D03*
X386777Y159005D03*
X373922Y193103D03*
X374000Y190350D03*
X379750Y213500D03*
X376300Y211000D03*
X382600Y222600D03*
X382750Y229000D03*
X379700Y219200D03*
X376300Y216200D03*
X393331Y118043D03*
X393351Y115107D03*
X397650Y115500D03*
X401749Y112418D03*
X401159Y119636D03*
X401353Y116562D03*
X396251Y117999D03*
X398500Y125604D03*
X398512Y122815D03*
X401500Y125600D03*
X392998Y133968D03*
X396148D03*
X396321Y136987D03*
X402561Y137000D03*
X399298Y137118D03*
X392998D03*
X402400Y140163D03*
X403132Y144374D03*
X396148Y140268D03*
X399298D03*
X392599Y181686D03*
X403600Y182400D03*
Y180200D03*
X399385Y171686D03*
X396225D03*
X390025Y174672D03*
X393085Y171686D03*
Y174836D03*
X392600Y190600D03*
X396200Y194700D03*
X392624Y184537D03*
X389500Y193600D03*
X397307Y186607D03*
X395600Y184100D03*
Y190300D03*
X403022Y192094D03*
X402967Y195005D03*
X404529Y118507D03*
X405900Y121700D03*
X409110Y114910D03*
X405200Y115343D03*
X412462Y115713D03*
X409196Y118195D03*
X404900Y124600D03*
X406200Y127400D03*
X412100Y135600D03*
X417753Y131322D03*
X415700Y143100D03*
X410302Y141864D03*
X405990Y144251D03*
X409096Y143963D03*
X406042Y147025D03*
X415100Y149800D03*
X407399Y142561D03*
X408837Y149809D03*
X414800Y162600D03*
X411800Y162700D03*
X414572Y165913D03*
X411356Y165732D03*
X413314Y154908D03*
X408242Y184624D03*
X405231Y184976D03*
X408200Y190500D03*
X408100Y193600D03*
X428100Y120000D03*
X424900Y121213D03*
X431504Y126061D03*
X424982Y126500D03*
X434700Y131800D03*
X432542Y136898D03*
X426982Y131334D03*
X419499Y139064D03*
X423496Y144000D03*
X428363Y141756D03*
X423945Y165221D03*
X421710Y167230D03*
X431130Y166660D03*
X420804Y162659D03*
X420900Y160037D03*
X431620Y154620D03*
X422363Y154700D03*
X431270Y193425D03*
X438700Y112900D03*
X434960Y114529D03*
X434700Y128200D03*
X443443Y144757D03*
X437398Y146257D03*
X435004Y142110D03*
X434834Y163817D03*
X438742Y197224D03*
X435642Y194824D03*
X437921Y192956D03*
X508700Y14607D03*
X511589Y30295D03*
X507839Y30362D03*
X523453Y12360D03*
X511800Y12507D03*
X520700Y14807D03*
X518769Y22907D03*
X515484D03*
X525753Y30893D03*
X522733Y32832D03*
X511640Y255956D03*
X514137Y256089D03*
X522908Y255117D03*
X526715Y254700D03*
X511736Y273001D03*
X514900Y271350D03*
X522992Y270700D03*
X525845Y272863D03*
X517846Y262489D03*
X521131D03*
X537964Y12317D03*
X532500Y13407D03*
X541114Y12307D03*
X532472Y20515D03*
X537410Y20584D03*
X541950Y33340D03*
X532542Y33307D03*
X537200Y33207D03*
X547500Y12507D03*
X553720Y12297D03*
X550234Y14997D03*
X553797Y20496D03*
X549500Y29107D03*
X553250Y33207D03*
X547306Y33134D03*
X558448Y12407D03*
X566040Y12317D03*
X566000Y16507D03*
X572200Y28707D03*
X558500Y20507D03*
X573200Y19907D03*
X565470Y33287D03*
X573242Y32462D03*
X560635Y33264D03*
X573470Y12347D03*
X578620Y12357D03*
X585280Y12267D03*
X583700Y28207D03*
X578600Y20307D03*
X579100Y33207D03*
X585550Y33340D03*
X587700Y255300D03*
X587642Y252206D03*
X588036Y273089D03*
X588400Y270300D03*
X590000Y14007D03*
X594500Y4007D03*
X600896Y12407D03*
X601000Y20507D03*
X590500Y30507D03*
X594200Y33607D03*
X600360Y33287D03*
X591300Y255010D03*
X591342Y252206D03*
X591500Y270100D03*
X591536Y273000D03*
X605700Y12407D03*
X615852Y19807D03*
X615907Y24856D03*
X610800Y14807D03*
X605728Y20518D03*
X606700Y255600D03*
X604074Y254394D03*
X609500Y254900D03*
X609937Y252106D03*
X609896Y272889D03*
X608996Y270206D03*
X605100Y270100D03*
X605065Y272967D03*
X623532Y20007D03*
X623555Y25107D03*
X619607Y19807D03*
X627255Y25107D03*
X627231Y19907D03*
X630955Y25207D03*
X631000Y20107D03*
X634555Y25307D03*
X634757Y20207D03*
X619730Y24864D03*
X638400Y20607D03*
X638290Y25674D03*
X642246Y25807D03*
X642451Y20707D03*
X635043Y252106D03*
X638900Y254809D03*
X637288Y270100D03*
X637337Y272944D03*
X659400Y25907D03*
Y20474D03*
X663202Y25973D03*
X655602Y25223D03*
X663200Y20956D03*
X655700Y20225D03*
X675990Y12357D03*
X676600Y20307D03*
X671500Y15007D03*
X671900Y30707D03*
X675970Y33267D03*
X687602Y12439D03*
X694200Y13507D03*
X681280Y12457D03*
X684500Y15507D03*
X689595Y27883D03*
X685400Y28307D03*
X681700Y20507D03*
X694205Y20302D03*
X693700Y33107D03*
X681280Y33340D03*
X687900Y33327D03*
X699503Y12482D03*
X706360Y12397D03*
X705604Y16949D03*
X710813Y28796D03*
X699104Y20495D03*
X707157Y33333D03*
X700940Y33340D03*
X714000Y12407D03*
X719110Y12347D03*
X725530Y12507D03*
X714100Y20607D03*
X719220Y20553D03*
X721074Y30514D03*
X718350Y33107D03*
X712450Y33340D03*
X725653Y32654D03*
X737300Y12307D03*
X732110Y12267D03*
X728500Y15507D03*
X742100Y28107D03*
X732000Y20307D03*
X736748D03*
X728500Y27907D03*
X733474Y33340D03*
X738487Y33094D03*
X730400Y255400D03*
X732200Y252200D03*
X741560Y255000D03*
X730400Y272850D03*
X732740Y270200D03*
X741200Y270500D03*
X735168Y262489D03*
X738453D03*
X745100Y12256D03*
X744900Y20500D03*
X745000Y23000D03*
X744800Y33007D03*
X744437Y252189D03*
X744200Y272600D03*
G54D23*
G01X37900Y195300D02*
X37400Y194800D01*
Y187100D01*
X40100Y184400D01*
X47600D01*
X63400Y168600D01*
X88522D01*
X91074Y166048D01*
Y157927D01*
X92501Y156500D01*
X112325Y136674D01*
Y131415D01*
X111375Y130465D01*
Y76171D01*
X125100Y62446D01*
Y58483D01*
X130534Y53049D01*
X132355D01*
X132356Y53050D01*
X137261D01*
X140900Y49411D01*
Y48627D01*
X146827Y42700D01*
X216300D01*
X219900Y39100D01*
G01X58800Y177000D02*
Y176200D01*
X64550Y170450D01*
X89313D01*
X92924Y166839D01*
Y158702D01*
X116675Y134951D01*
Y133148D01*
X113225Y129698D01*
Y76938D01*
X126950Y63213D01*
Y59250D01*
X131300Y54900D01*
X139875D01*
X149375Y45400D01*
X217800D01*
X219600Y43600D01*
X222600D01*
X231700Y34500D01*
X285969D01*
X288575Y37106D01*
Y37192D01*
X302183Y50800D01*
X311950D01*
G01X322500Y254200D02*
X316800Y259900D01*
X274500D01*
X260850Y273550D01*
X185450D01*
X176725Y282275D01*
X77258D01*
X67000Y272017D01*
Y272000D01*
X60000Y265000D01*
Y260900D01*
X54900Y255800D01*
Y246400D01*
X56724Y244576D01*
Y243300D01*
G01X56800Y249613D02*
X62200Y255013D01*
Y255800D01*
X61500Y256500D01*
X60350D01*
X60000Y256850D01*
Y258295D01*
X60350Y258645D01*
X61850D01*
X62200Y258995D01*
Y264600D01*
X78025Y280425D01*
X175958D01*
X176478Y279905D01*
Y278978D01*
X176000Y278500D01*
Y278000D01*
X176571Y277429D01*
X177429D01*
X178000Y278000D01*
X178383D01*
X179202Y277181D01*
Y276455D01*
X178747Y276000D01*
Y275253D01*
X179253Y274747D01*
X180000D01*
X180253Y275000D01*
X180906D01*
X181453Y274453D01*
Y272454D01*
X182057Y271850D01*
X260145D01*
X260832Y271163D01*
Y269668D01*
X261500Y269000D01*
X262995D01*
X264497Y267498D01*
Y266503D01*
X265500Y265500D01*
X266495D01*
X267497Y264498D01*
Y263003D01*
X268000Y262500D01*
X269495D01*
X270497Y261498D01*
Y260003D01*
X271000Y259500D01*
X272495D01*
X273795Y258200D01*
X315000D01*
X319000Y254200D01*
G01X58102Y246471D02*
X59962Y248331D01*
X60456D01*
X62896Y245892D01*
X63390D01*
X64500Y247002D01*
Y247500D01*
X62565Y249435D01*
Y250934D01*
X64000Y252369D01*
Y263995D01*
X78580Y278575D01*
X172925D01*
X181350Y270150D01*
X257850D01*
X264013Y263987D01*
Y263493D01*
X262257Y261737D01*
Y261243D01*
X263001Y260499D01*
X263495D01*
X265251Y262255D01*
X265745D01*
X266489Y261511D01*
Y261017D01*
X264983Y259511D01*
Y259017D01*
X265727Y258273D01*
X266221D01*
X267727Y259779D01*
X268221D01*
X271500Y256500D01*
X313700D01*
X315500Y254700D01*
Y254100D01*
G01X342600Y277900D02*
X338700Y274000D01*
Y264289D01*
X326411Y252000D01*
X320417D01*
X318517Y250100D01*
X296948D01*
X282973Y236125D01*
X274664D01*
X259400Y251389D01*
Y257045D01*
X247995Y268450D01*
X180645D01*
X172220Y276875D01*
X79475D01*
X78200Y275600D01*
G01X120200Y45610D02*
X123410Y42400D01*
X128667D01*
X140567Y30500D01*
X314503D01*
X327852Y43849D01*
X332366D01*
X335393Y46876D01*
X342609D01*
X342991Y46800D01*
X344869D01*
X353000Y38669D01*
Y36000D01*
X356000Y33000D01*
X366815D01*
X371457Y37642D01*
G01X121295Y77502D02*
X124587D01*
X130267Y71822D01*
X161094D01*
X181400Y92128D01*
Y94657D01*
X183507Y96764D01*
Y99193D01*
X181951Y100749D01*
Y107089D01*
X184862Y110000D01*
X191589D01*
X206539Y124950D01*
X254964D01*
X262764Y132750D01*
X288128D01*
X292700Y137322D01*
Y138751D01*
X295711Y141762D01*
Y142986D01*
X303343Y150618D01*
Y152115D01*
X306474Y155246D01*
X309772D01*
X322335Y167809D01*
X324914D01*
X325497Y167226D01*
X327301D01*
X329442Y169367D01*
Y169463D01*
G01X121170Y80900D02*
X121200Y80930D01*
Y83912D01*
X125389Y88100D01*
X137178D01*
X146199Y97121D01*
Y122533D01*
X152416Y128750D01*
X155389D01*
X175339Y148700D01*
X177200D01*
G01X138000Y49800D02*
Y48910D01*
X155410Y31500D01*
X302436D01*
X306550Y35614D01*
Y38447D01*
X310951Y42848D01*
X318073D01*
X320900Y45675D01*
X331575D01*
X334626Y48726D01*
X345560D01*
X355296Y38990D01*
Y37006D01*
X356335Y35967D01*
X365845D01*
X367520Y37642D01*
G01X330027Y174119D02*
X329561D01*
X328191Y172749D01*
X325993D01*
X323303Y170059D01*
X321402D01*
X313074Y161731D01*
X305679D01*
X301093Y157145D01*
Y153787D01*
X286831Y139525D01*
X285563D01*
X283138Y137100D01*
X265769D01*
X265768Y137101D01*
X260962D01*
X256661Y132800D01*
X240725D01*
X237225Y129300D01*
X204736D01*
X193636Y118200D01*
X184998D01*
X177000Y110202D01*
Y99700D01*
X176225Y98925D01*
Y95366D01*
X176874Y94717D01*
Y89653D01*
X160493Y73272D01*
X131633D01*
X126092Y78813D01*
X125787D01*
G01X126000Y86200D02*
Y84700D01*
X135978Y74722D01*
X159892D01*
X175424Y90254D01*
Y94116D01*
X174775Y94765D01*
Y99949D01*
X175550Y100724D01*
Y111034D01*
X184166Y119650D01*
X193035D01*
X204135Y130750D01*
X236252D01*
X242052Y136550D01*
X258060D01*
X260061Y138551D01*
X266369D01*
X266370Y138550D01*
X282537D01*
X284962Y140975D01*
X286230D01*
X300343Y155088D01*
Y157456D01*
X305368Y162481D01*
X309081D01*
X320130Y173530D01*
X325338D01*
X325982Y174174D01*
X327600D01*
G01X134200Y86100D02*
X134700Y85600D01*
X139847D01*
X152855Y98608D01*
Y100080D01*
X152775Y100160D01*
Y109424D01*
X153950Y110599D01*
Y118450D01*
X171575Y136075D01*
X180426D01*
X187351Y143000D01*
X191529D01*
X197993Y149464D01*
X219785D01*
X224347Y154026D01*
X225547D01*
X225548Y154025D01*
X256576D01*
X272480Y169929D01*
X290845D01*
X297241Y176325D01*
X310291D01*
X315915Y181949D01*
X320597D01*
X322146Y180400D01*
X323163D01*
X323500Y180063D01*
G01X129300Y84900D02*
X130050Y84150D01*
X140448D01*
X154305Y98007D01*
Y100044D01*
X181261Y127000D01*
X183734D01*
X200398Y143664D01*
X225327D01*
X229888Y148225D01*
X258980D01*
X262430Y151675D01*
X273036D01*
X274886Y149825D01*
X284573D01*
X286900Y152152D01*
Y157651D01*
X299749Y170500D01*
X305230D01*
X306612Y171882D01*
G01X137138Y76512D02*
X140353D01*
X162980Y99139D01*
Y106668D01*
X181812Y125500D01*
X184285D01*
X200999Y142214D01*
X225928D01*
X230489Y146775D01*
X283826D01*
X288350Y151299D01*
Y157050D01*
X300300Y169000D01*
X306152D01*
X309112Y171960D01*
G01X310579Y182800D02*
X309266Y184113D01*
X295263D01*
X294862Y184513D01*
X291223D01*
X290110Y183400D01*
X272934D01*
X272259Y182725D01*
X254411D01*
X250601Y178915D01*
X247615D01*
X236700Y168000D01*
X234937D01*
X233657Y169280D01*
X232185D01*
X231035Y168130D01*
X227340D01*
X226970Y168500D01*
X197477D01*
X193502Y164525D01*
X189370D01*
X183616Y158771D01*
X177371D01*
X155125Y136525D01*
X150023D01*
X134725Y121227D01*
Y100787D01*
X137475Y98037D01*
Y94175D01*
X136600Y93300D01*
G01X301745Y181788D02*
X301570Y181613D01*
X292425D01*
X288787Y177975D01*
X259772D01*
X251797Y170000D01*
X243002D01*
X237192Y164190D01*
X225879D01*
X224469Y165600D01*
X207549D01*
X203949Y162000D01*
X198147D01*
X187422Y151275D01*
X174075D01*
X156425Y133625D01*
X151225D01*
X140988Y123388D01*
Y109411D01*
X136500Y104923D01*
G01X304400Y182000D02*
X303037Y183363D01*
X300332D01*
X300032Y183063D01*
X291824D01*
X288186Y179425D01*
X255814D01*
X247989Y171600D01*
X242551D01*
X236591Y165640D01*
X226480D01*
X225070Y167050D01*
X200727D01*
X186477Y152800D01*
X173549D01*
X155824Y135075D01*
X150624D01*
X138950Y123401D01*
Y111030D01*
X136540Y108620D01*
G01X126950Y125200D02*
X134625Y132875D01*
X140680D01*
X146400Y138595D01*
G01X300900Y46900D02*
X297849Y43849D01*
X297249D01*
X286900Y33500D01*
X230423D01*
X221523Y42400D01*
X218500D01*
X217000Y43900D01*
X148138D01*
X143688Y48350D01*
G01X154294Y76506D02*
X159625D01*
X173974Y90855D01*
Y93515D01*
X171225Y96264D01*
Y99025D01*
X174100Y101900D01*
Y110433D01*
X174099Y110434D01*
Y111634D01*
X183565Y121100D01*
X189100D01*
X200200Y132200D01*
X222580D01*
X225880Y135500D01*
X227834D01*
X229673Y133661D01*
X237112D01*
X245576Y142125D01*
X265336D01*
X267436Y140025D01*
X270336D01*
X270361Y140000D01*
X281936D01*
X284361Y142425D01*
X285629D01*
X292700Y149496D01*
Y153228D01*
X297347Y157875D01*
X297964D01*
X305723Y165634D01*
X309391D01*
X318037Y174280D01*
X325027D01*
X326346Y175599D01*
X331034D01*
X332246Y176811D01*
Y177644D01*
X333702Y179100D01*
X336418D01*
X337863Y180545D01*
G01X330821Y177402D02*
X329563D01*
X328299Y178666D01*
X327110D01*
X326332Y177888D01*
X319523D01*
X309135Y167500D01*
X303300D01*
X297575Y161775D01*
X296347D01*
X295425Y160853D01*
Y160055D01*
X289800Y154430D01*
Y150698D01*
X284427Y145325D01*
X244674D01*
X235910Y136561D01*
X230875D01*
X229775Y137661D01*
Y140436D01*
X228736Y141475D01*
X227264D01*
X226544Y140755D01*
X226535Y140764D01*
X201600D01*
X184836Y124000D01*
X182363D01*
X164430Y106067D01*
Y90033D01*
X150894Y76497D01*
G01X154550Y102800D02*
X181400Y129650D01*
Y130700D01*
X187000Y136300D01*
X190983D01*
X199797Y145114D01*
X221588D01*
X226149Y149675D01*
X258379D01*
X262704Y154000D01*
X275000D01*
X275875Y154875D01*
Y164375D01*
X277079Y165579D01*
X292648D01*
X293470Y166401D01*
X293599D01*
X299148Y171950D01*
X303568D01*
X305089Y173471D01*
Y173886D01*
X305091Y173888D01*
G01X150670Y102720D02*
Y109589D01*
X152500Y111419D01*
Y119051D01*
X171624Y138175D01*
X180475D01*
X196175Y153875D01*
X197714D01*
X199164Y152425D01*
X220695D01*
X223945Y155675D01*
X240185D01*
X242445Y157935D01*
X258435D01*
X271879Y171379D01*
X290244D01*
X296128Y177263D01*
X310168D01*
X315604Y182699D01*
X321317D01*
X322529Y181488D01*
X324091D01*
X324712Y180867D01*
X327726D01*
X327759Y180900D01*
X330280D01*
G01X307200Y182000D02*
X305363Y180163D01*
X293026D01*
X289388Y176525D01*
X260373D01*
X252348Y168500D01*
X243553D01*
X236928Y161875D01*
X226143D01*
X223868Y164150D01*
X208150D01*
X201425Y157425D01*
X195623D01*
X179273Y141075D01*
X169907D01*
X156032Y127200D01*
X153059D01*
X147750Y121891D01*
Y102674D01*
X151080Y99344D01*
G01X154550Y106200D02*
Y109148D01*
X155400Y109998D01*
Y116236D01*
X156439Y117275D01*
X157797D01*
X175147Y134625D01*
X181027D01*
X187952Y141550D01*
X192130D01*
X198594Y148014D01*
X220386D01*
X224947Y152575D01*
X257177D01*
X273081Y168479D01*
X291446D01*
X298542Y175575D01*
X310602D01*
X313665Y178638D01*
X326021D01*
X326799Y179416D01*
X331016D01*
X332500Y180900D01*
G01X309200Y180500D02*
X307413Y178713D01*
X295141D01*
X291503Y175075D01*
X263958D01*
X262300Y173417D01*
Y171124D01*
X254926Y163750D01*
X246169D01*
X239544Y157125D01*
X223344D01*
X221219Y155000D01*
X204726D01*
X203751Y155975D01*
X196224D01*
X179874Y139625D01*
X170508D01*
X155690Y124807D01*
X153693D01*
G01X172199Y91591D02*
X169775Y94015D01*
Y109361D01*
X182964Y122550D01*
X187350D01*
X200791Y135991D01*
X206509D01*
X208600Y133900D01*
X221400D01*
X224450Y136950D01*
X228435D01*
X230274Y135111D01*
X236511D01*
X245275Y143875D01*
X285028D01*
X291250Y150097D01*
Y153829D01*
X296046Y158625D01*
X297653D01*
X305528Y166500D01*
X309196D01*
X319834Y177138D01*
X327495D01*
X327598Y177241D01*
X327708D01*
G01X158305Y112180D02*
X160700Y114575D01*
Y118127D01*
X175748Y133175D01*
X181628D01*
X186853Y138400D01*
X191031D01*
X199195Y146564D01*
X220987D01*
X225548Y151125D01*
X257778D01*
X264628Y157975D01*
X267786D01*
X272325Y162514D01*
Y164036D01*
X275318Y167029D01*
X292047D01*
X298543Y173525D01*
X302210D01*
X302591Y173906D01*
G01X188900Y91800D02*
Y91400D01*
X186075Y88575D01*
Y67775D01*
X173983Y55683D01*
Y52117D01*
X179200Y46900D01*
X218600D01*
X220500Y45000D01*
X223400D01*
X228700Y39700D01*
X235017D01*
X238900Y35817D01*
X272517D01*
X279200Y42500D01*
X291100D01*
X301250Y52650D01*
X346870D01*
X355863Y43657D01*
X356432D01*
G01X178000Y97300D02*
Y98600D01*
X178450Y99050D01*
Y109601D01*
X181800Y112951D01*
X183000D01*
X183001Y112950D01*
X190437D01*
X205337Y127850D01*
X253762D01*
X261563Y135651D01*
X265167D01*
X265168Y135650D01*
X283739D01*
X285864Y137775D01*
X287622D01*
X301843Y151996D01*
Y156834D01*
X305990Y160981D01*
X313385D01*
X321713Y169309D01*
X323614D01*
X326304Y171999D01*
X334615D01*
X336718Y174102D01*
X337000D01*
G01X179400Y94200D02*
X179900Y94700D01*
Y109000D01*
X182400Y111500D01*
X191038D01*
X205938Y126400D01*
X254363D01*
X262164Y134201D01*
X264566D01*
X264567Y134200D01*
X287527D01*
X291250Y137923D01*
Y139352D01*
X294961Y143063D01*
Y143297D01*
X302593Y150929D01*
Y156523D01*
X306301Y160231D01*
X313696D01*
X322024Y168559D01*
X325225D01*
X325808Y167976D01*
X326990D01*
X327824Y168810D01*
Y169861D01*
X328851Y170888D01*
X330112D01*
X331478Y169522D01*
X332353D01*
G01X189106Y97235D02*
X195521Y103650D01*
X211837D01*
X216087Y99400D01*
X228536D01*
X229111Y98825D01*
X239600D01*
X244725Y103950D01*
X259324D01*
X259820Y103454D01*
G01X201650Y111200D02*
Y116486D01*
X205114Y119950D01*
X206650D01*
X207484Y119116D01*
X213221D01*
X214705Y120600D01*
X256767D01*
X262167Y126000D01*
X288498D01*
X291000Y128502D01*
Y129469D01*
X294956Y133425D01*
Y133714D01*
X296564Y135322D01*
Y136311D01*
G01X325746Y133702D02*
X316141D01*
X312939Y130500D01*
X310961D01*
X300549Y120088D01*
Y115187D01*
X293587Y108225D01*
X279759D01*
X261384Y89850D01*
X253116D01*
X244641Y81375D01*
X234873D01*
X226098Y72600D01*
X214817D01*
X213800Y73617D01*
Y84000D01*
X212300Y85500D01*
G01X335303Y135178D02*
X332126D01*
X330602Y136702D01*
X325196D01*
X323699Y138198D01*
X320862D01*
X318352Y135688D01*
X310165D01*
X309902Y135425D01*
X308010D01*
X305873Y133288D01*
Y129703D01*
X306324Y129252D01*
Y126936D01*
X299724Y120336D01*
Y117207D01*
X292592Y110075D01*
X278992D01*
X265394Y96477D01*
X261791D01*
X259759Y98509D01*
X249220D01*
X237436Y86725D01*
X213900D01*
X213350Y87275D01*
X211375D01*
X209550Y85450D01*
Y72633D01*
X213283Y68900D01*
X213284D01*
X214942Y67242D01*
G01X325418Y127349D02*
X324700D01*
X323598Y126247D01*
X315747D01*
X313740Y124240D01*
Y121740D01*
X312400Y120400D01*
X307165D01*
X306534Y119769D01*
X306532Y119768D01*
X306419Y119726D01*
X305226D01*
X302799Y117299D01*
Y112005D01*
X302185Y111391D01*
Y110085D01*
X294775Y102675D01*
X282060D01*
X263685Y84300D01*
X258289D01*
X248525Y74536D01*
Y70742D01*
X242958Y65175D01*
X236500D01*
X230925Y70750D01*
X214050D01*
X211600Y73200D01*
Y82100D01*
G01X309220Y153698D02*
X309317Y153601D01*
Y152136D01*
X301606Y144425D01*
X300047D01*
X298375Y142753D01*
Y140635D01*
X294900Y137160D01*
Y135420D01*
X289550Y130070D01*
Y129103D01*
X287897Y127450D01*
X261566D01*
X256166Y122050D01*
X214104D01*
X212954Y120900D01*
X209900D01*
G01X206605Y121741D02*
X208364Y123500D01*
X255565D01*
X263365Y131300D01*
X288729D01*
X294150Y136721D01*
Y138150D01*
X297625Y141625D01*
Y143064D01*
X299736Y145175D01*
X300128D01*
X301109Y146156D01*
G01X219900Y39100D02*
X226500Y32500D01*
X302233D01*
X305700Y35967D01*
Y38800D01*
X310850Y43950D01*
X317650D01*
X320400Y46700D01*
X325802D01*
X327577Y48475D01*
G01X229300Y42950D02*
X230879Y41371D01*
X236852D01*
X236854Y41372D01*
X236905Y41382D01*
X236948Y41411D01*
X238312Y42775D01*
X263175D01*
X265200Y44800D01*
X269800D01*
G01X301300Y97000D02*
X300881Y96581D01*
X293498D01*
X292250Y95333D01*
Y92356D01*
X280770Y80876D01*
X274300D01*
X268799Y75375D01*
X258392D01*
X243000Y59983D01*
Y59175D01*
X240975Y57150D01*
X230050D01*
X225500Y61700D01*
X223800D01*
G01X230400Y63000D02*
X232150Y61250D01*
X241650D01*
X257625Y77225D01*
X268032D01*
X273533Y82726D01*
X280003D01*
X290400Y93123D01*
Y96100D01*
X292731Y98431D01*
X299231D01*
X299300Y98500D01*
G01X330163Y142008D02*
X328642Y143529D01*
X318429D01*
X314450Y139550D01*
X308934D01*
X302724Y133340D01*
Y125458D01*
X298149Y120883D01*
Y120442D01*
X291182Y113475D01*
X277625D01*
X275049Y116051D01*
X273558D01*
X273557Y116050D01*
X265243D01*
X256468Y107275D01*
X243468D01*
X238468Y102275D01*
X230219D01*
X227894Y104600D01*
G01X227800Y101200D02*
X228929D01*
X229404Y100725D01*
X239125D01*
X243900Y105500D01*
X257850D01*
X266750Y114400D01*
X274507D01*
X276982Y111925D01*
X291825D01*
X298899Y118999D01*
Y120572D01*
X305574Y127247D01*
Y128940D01*
X304925Y129589D01*
Y133402D01*
X307698Y136175D01*
X309591D01*
X309854Y136438D01*
X316757D01*
X320119Y139800D01*
X325672D01*
X325731Y139859D01*
X326913D01*
X327072Y139700D01*
X339300D01*
X344218Y144618D01*
X346591D01*
X348045Y146072D01*
X348743D01*
G01X346000Y146043D02*
X344343Y147700D01*
X328000D01*
X327981Y147681D01*
X326321D01*
X324010Y145370D01*
X312116D01*
X301150Y134404D01*
Y127829D01*
X289895Y116575D01*
X283886D01*
X282211Y118250D01*
X265250D01*
X255825Y108825D01*
X242825D01*
X237825Y103825D01*
X233350D01*
X230875Y106300D01*
G01X335450Y150900D02*
X335000D01*
X333475Y149375D01*
X329137D01*
X327768Y150744D01*
X324044D01*
X319420Y146120D01*
X311805D01*
X300400Y134715D01*
Y128500D01*
X294391Y122491D01*
X293618D01*
X289252Y118125D01*
X284529D01*
X282854Y119800D01*
X264607D01*
X255182Y110375D01*
X230071D01*
X228000Y108304D01*
G01X240300Y67200D02*
X239250Y68250D01*
Y72850D01*
X254400Y88000D01*
X262151D01*
X280526Y106375D01*
X294134D01*
X301299Y113540D01*
Y119777D01*
X311272Y129750D01*
X313250D01*
X316203Y132703D01*
X324729D01*
X325155Y132277D01*
X326337D01*
X327063Y133003D01*
X337683D01*
X339754Y135074D01*
Y136636D01*
X341342Y138224D01*
G01X342533Y133822D02*
X342509Y133798D01*
X339798D01*
X338253Y132253D01*
X327374D01*
X326648Y131527D01*
X324844D01*
X324418Y131953D01*
X316514D01*
X313561Y129000D01*
X311583D01*
X302049Y119466D01*
Y112318D01*
X294256Y104525D01*
X281293D01*
X262918Y86150D01*
X255167D01*
X243200Y74183D01*
Y73700D01*
G01X264600Y173100D02*
X264833Y172867D01*
Y166950D01*
X257668Y159785D01*
X244715D01*
G01X262700Y191500D02*
X264125Y190075D01*
X267175D01*
X268410Y191310D01*
X284364D01*
X285564Y190110D01*
X288110D01*
X289100Y191100D01*
X294600D01*
X296600Y189100D01*
G01X339491Y143163D02*
X339467D01*
X338280Y144350D01*
X317650D01*
X313600Y140300D01*
X308623D01*
X301900Y133577D01*
Y126386D01*
X290539Y115025D01*
X282925D01*
X281475Y116475D01*
G01X291201Y225025D02*
Y229901D01*
X305500Y244200D01*
X320962D01*
X322862Y246100D01*
X340600D01*
X372000Y277500D01*
X423200D01*
X426600Y274100D01*
G01X429900Y274940D02*
X425490Y279350D01*
X371233D01*
X339833Y247950D01*
X322095D01*
X320195Y246050D01*
X300450D01*
X287802Y233402D01*
Y225200D01*
G01X299300Y98500D02*
X305035Y104235D01*
Y115108D01*
X306052Y116125D01*
X310145D01*
X310662Y116642D01*
X311958D01*
X317608Y122292D01*
Y124108D01*
X318700Y125200D01*
X325285D01*
X326843Y126758D01*
Y127940D01*
X325114Y129669D01*
X324131D01*
X323900Y129900D01*
G01X346300Y143000D02*
Y141482D01*
X345533Y140715D01*
Y140601D01*
X344028Y139096D01*
Y132987D01*
X343294Y132253D01*
X339753D01*
X339000Y131500D01*
X334500D01*
X331200Y128200D01*
X329558D01*
X325455Y124097D01*
X323197D01*
X312400Y113300D01*
X310400D01*
X309000Y114700D01*
G01X348675Y143326D02*
Y142796D01*
X346283Y140404D01*
Y140290D01*
X344778Y138785D01*
Y132676D01*
X343605Y131503D01*
X340064D01*
X339311Y130750D01*
X335033D01*
X332552Y128269D01*
Y126908D01*
X332900Y126560D01*
Y124920D01*
X331791Y123811D01*
X328717D01*
X327738Y122832D01*
Y121789D01*
X326904Y120955D01*
X322155D01*
X313700Y112500D01*
X308900D01*
X306700Y114700D01*
G01X338329Y135665D02*
X336417Y133753D01*
X332384D01*
X330260Y135877D01*
X324853D01*
X323282Y137448D01*
X322100D01*
X319590Y134938D01*
X312399D01*
X311811Y134350D01*
X308909D01*
X307298Y132739D01*
Y132697D01*
G01X441281Y17025D02*
X440856D01*
X438721Y19160D01*
X425080D01*
X421000Y23240D01*
Y46859D01*
X414159Y53700D01*
X364130D01*
X359001Y48571D01*
Y43101D01*
X357400Y41500D01*
X355403D01*
X346327Y50576D01*
X316727D01*
X315168Y49017D01*
Y48993D01*
X314800Y48625D01*
G01X432200Y9103D02*
X429503Y11800D01*
X425342D01*
X419150Y17992D01*
Y46092D01*
X413392Y51850D01*
X364897D01*
X360851Y47804D01*
Y41580D01*
X356971Y37700D01*
G01X422000Y9103D02*
X416599Y14504D01*
Y45034D01*
X412333Y49300D01*
X370300D01*
X368259Y47259D01*
Y41804D01*
X367497Y41042D01*
G01X428800Y9103D02*
X427003Y10900D01*
X425039D01*
X418300Y17639D01*
Y45739D01*
X413039Y51000D01*
X366558D01*
X362626Y47068D01*
G01X425400Y9103D02*
X417450Y17053D01*
Y45386D01*
X412686Y50150D01*
X369505D01*
X366484Y47129D01*
G01X460400Y275200D02*
X467876Y282676D01*
X747603D01*
X761887Y268392D01*
Y247783D01*
X736950Y222846D01*
Y209267D01*
X748225Y197992D01*
Y190797D01*
X739617Y182189D01*
X733181D01*
X727800Y176808D01*
Y176600D01*
G01X464000Y275200D02*
X469626Y280826D01*
X746836D01*
X760037Y267625D01*
Y248550D01*
X735100Y223613D01*
Y208500D01*
X746375Y197225D01*
Y191564D01*
X738851Y184040D01*
X732415D01*
X724400Y176025D01*
G01X472400Y275100D02*
X474426Y277126D01*
X745674D01*
X748637Y274163D01*
Y259746D01*
X750650Y257733D01*
Y247398D01*
X729331Y226079D01*
Y215220D01*
X711955Y197844D01*
X706305D01*
X693850Y185389D01*
Y169769D01*
X664790Y140709D01*
Y125790D01*
X656000Y117000D01*
X646094D01*
X632894Y130200D01*
X614700D01*
X608360Y123860D01*
Y121800D01*
G01X469000Y275200D02*
X472776Y278976D01*
X746069D01*
X750487Y274558D01*
Y260513D01*
X752500Y258500D01*
Y246631D01*
X731225Y225356D01*
Y214435D01*
X712740Y195950D01*
X707090D01*
X695700Y184560D01*
Y168940D01*
X666880Y140120D01*
Y124880D01*
X657000Y115000D01*
X644700D01*
X631700Y128000D01*
X615620D01*
X612120Y124500D01*
Y121750D01*
G01X605600Y186650D02*
X602204D01*
X596650Y181096D01*
Y180350D01*
X596300Y180000D01*
X595600D01*
X595250Y180350D01*
Y181250D01*
X594900Y181600D01*
X594200D01*
X593850Y181250D01*
Y179850D01*
X593500Y179500D01*
X592800D01*
X592450Y179850D01*
Y181250D01*
X592100Y181600D01*
X591400D01*
X591050Y181250D01*
Y179850D01*
X590700Y179500D01*
X590000D01*
X589650Y179850D01*
Y181250D01*
X589300Y181600D01*
X588600D01*
X588250Y181250D01*
Y179850D01*
X587900Y179500D01*
X566350D01*
X566000Y179850D01*
Y181275D01*
X566350Y181625D01*
X583125D01*
X584800Y183300D01*
G01X786500Y13500D02*
X785284D01*
X779116Y7332D01*
X755168D01*
X746666Y15834D01*
Y21334D01*
X745000Y23000D01*
G01X790500Y11000D02*
X785401D01*
X779883Y5482D01*
X754518D01*
X744900Y15100D01*
Y20500D01*
G54D14*
X756400Y110500D03*
X786500Y13500D03*
X790500Y11000D03*
X799000Y121500D03*
Y125500D03*
X800400Y158500D03*
X799900Y168800D03*
G54D24*
G01X328510Y218320D02*
X328363Y218467D01*
X317467D01*
X303500Y204500D01*
X300300D01*
X297010Y201210D01*
X258951D01*
X255436Y204725D01*
X243191D01*
X235316Y196850D01*
X222589D01*
X209012Y183273D01*
X194788D01*
X193361Y184700D01*
X160339D01*
X151000Y175361D01*
Y163500D01*
X148300Y160800D01*
X126714D01*
X110189Y177325D01*
X98979D01*
X92654Y183650D01*
X71403D01*
X64403Y190650D01*
X60210D01*
X42850Y208010D01*
Y218231D01*
X40981Y220100D01*
X39000D01*
X37900Y219000D01*
G01Y222500D02*
X39000Y221400D01*
X41520D01*
X44150Y218770D01*
Y208549D01*
X60749Y191950D01*
X64942D01*
X71942Y184950D01*
X93193D01*
X99518Y178625D01*
X110728D01*
X127253Y162100D01*
X147761D01*
X149700Y164039D01*
Y175900D01*
X159800Y186000D01*
X180591D01*
X181431Y186840D01*
X182781D01*
X183621Y186000D01*
X184971D01*
X185811Y186840D01*
X187161D01*
X188001Y186000D01*
X193900D01*
X195327Y184573D01*
X208473D01*
X222050Y198150D01*
X234777D01*
X242652Y206025D01*
X255975D01*
X259490Y202510D01*
X296471D01*
X299761Y205800D01*
X302961D01*
X316928Y219767D01*
X326767D01*
X327024Y220024D01*
G01X342400Y217900D02*
X340646D01*
X335246Y223300D01*
X324100D01*
X322900Y222100D01*
X316100D01*
X302000Y208000D01*
X299150D01*
X296110Y204960D01*
X260640D01*
X257125Y208475D01*
X243761D01*
X240807Y211429D01*
X239610D01*
X237861Y209680D01*
Y204699D01*
X233762Y200600D01*
X220721D01*
X216396Y196275D01*
X173414D01*
X165639Y188500D01*
X156400D01*
X153900Y191000D01*
X152000D01*
X149500Y188500D01*
X142600D01*
X140100Y191000D01*
X136400D01*
X126900Y181500D01*
X100108D01*
X94208Y187400D01*
X81300D01*
X70919Y197781D01*
X60023D01*
X46600Y211204D01*
Y221100D01*
X40400Y227300D01*
X39200D01*
X37900Y226000D01*
G01X342400Y219200D02*
X341185D01*
X335785Y224600D01*
X323561D01*
X322361Y223400D01*
X315561D01*
X301461Y209300D01*
X298611D01*
X295571Y206260D01*
X261179D01*
X257664Y209775D01*
X244300D01*
X241346Y212729D01*
X239071D01*
X236561Y210219D01*
Y205238D01*
X233223Y201900D01*
X220182D01*
X215857Y197575D01*
X172875D01*
X165100Y189800D01*
X156939D01*
X154439Y192300D01*
X151461D01*
X148961Y189800D01*
X143139D01*
X140639Y192300D01*
X135861D01*
X126361Y182800D01*
X100647D01*
X94747Y188700D01*
X81839D01*
X71458Y199081D01*
X60562D01*
X47900Y211743D01*
Y221639D01*
X40939Y228600D01*
X38800D01*
X37900Y229500D01*
G01X331142Y233658D02*
X329897D01*
X321539Y225300D01*
X314689D01*
X300889Y211500D01*
X298000D01*
X295210Y208710D01*
X268451D01*
X267080Y210080D01*
X261436Y215725D01*
X245228D01*
X244388Y214885D01*
X243038D01*
X242198Y215725D01*
X238602D01*
X227727Y204850D01*
X213989D01*
X210939Y201800D01*
X205075D01*
X204235Y200960D01*
X202885D01*
X202045Y201800D01*
X200695D01*
X199855Y200960D01*
X198505D01*
X197665Y201800D01*
X189304D01*
X187754Y200250D01*
X170134D01*
X166934Y197050D01*
X143450D01*
X141900Y198600D01*
X135362D01*
X123656Y186894D01*
X122306D01*
X121466Y186054D01*
X120116D01*
X119276Y186894D01*
X117926D01*
X117086Y186054D01*
X115736D01*
X114896Y186894D01*
X113546D01*
X112706Y186054D01*
X111356D01*
X110516Y186894D01*
X108463D01*
X107446Y187911D01*
X106258D01*
X105304Y188866D01*
Y190053D01*
X101407Y193950D01*
X99564D01*
X98724Y193110D01*
X97374D01*
X96534Y193950D01*
X95184D01*
X94344Y193110D01*
X92994D01*
X92154Y193950D01*
X90804D01*
X89964Y193110D01*
X88614D01*
X87774Y193950D01*
X80207D01*
X71657Y202500D01*
X60850D01*
X50350Y213000D01*
Y225550D01*
X41800Y234100D01*
X39000D01*
X37900Y233000D01*
G01X328945Y235846D02*
Y234545D01*
X321000Y226600D01*
X314150D01*
X300350Y212800D01*
X297461D01*
X294671Y210010D01*
X268990D01*
X261975Y217025D01*
X238063D01*
X227188Y206150D01*
X213450D01*
X210400Y203100D01*
X188765D01*
X187215Y201550D01*
X169595D01*
X166395Y198350D01*
X143989D01*
X142439Y199900D01*
X134823D01*
X123117Y188194D01*
X109002D01*
X101946Y195250D01*
X80746D01*
X72196Y203800D01*
X61389D01*
X51650Y213539D01*
Y226089D01*
X42339Y235400D01*
X39100D01*
X38000Y236500D01*
G01Y250500D02*
X38950Y249550D01*
X41889D01*
X62000Y229439D01*
Y224796D01*
X78171Y208625D01*
X102014D01*
X105800Y204839D01*
Y202004D01*
X107929Y199875D01*
X119849D01*
X133624Y213650D01*
X154271D01*
X156871Y211050D01*
X172861D01*
X175461Y213650D01*
X224080D01*
X236555Y226125D01*
X275114D01*
X281789Y219450D01*
X294254D01*
X298120Y223316D01*
Y228055D01*
X304265Y234200D01*
X315561D01*
X316980Y235619D01*
Y236720D01*
X316000Y237700D01*
G01X37900Y247000D02*
X39150Y248250D01*
X41350D01*
X60700Y228900D01*
Y224257D01*
X64752Y220205D01*
Y219017D01*
X65706Y218063D01*
X66894D01*
X67849Y217108D01*
Y215920D01*
X68803Y214966D01*
X69991D01*
X77632Y207325D01*
X101475D01*
X104500Y204300D01*
Y201465D01*
X107390Y198575D01*
X120388D01*
X121343Y199530D01*
X122531D01*
X123485Y200484D01*
Y201672D01*
X134163Y212350D01*
X153732D01*
X156332Y209750D01*
X173400D01*
X176000Y212350D01*
X224619D01*
X237094Y224825D01*
X242824D01*
X243664Y223985D01*
X245014D01*
X245854Y224825D01*
X247204D01*
X248044Y223985D01*
X249394D01*
X250234Y224825D01*
X257699D01*
X258539Y223985D01*
X259889D01*
X260729Y224825D01*
X262079D01*
X262919Y223985D01*
X264269D01*
X265109Y224825D01*
X266459D01*
X267299Y223985D01*
X268649D01*
X269489Y224825D01*
X274575D01*
X279154Y220246D01*
Y220245D01*
X281249Y218150D01*
X294793D01*
X299420Y222777D01*
Y227516D01*
X304804Y232900D01*
X316100D01*
X318280Y235080D01*
Y236880D01*
X319100Y237700D01*
G01X352600Y219450D02*
X347050D01*
X346200Y220300D01*
X343500D01*
X337300Y226500D01*
Y230800D01*
X329500Y238600D01*
X325900D01*
X324425Y237125D01*
Y235586D01*
X317839Y229000D01*
X306000D01*
X302775Y225775D01*
Y221260D01*
X295915Y214400D01*
X286339D01*
X285539Y213600D01*
X273975D01*
X268100Y219475D01*
X237048D01*
X226173Y208600D01*
X190800D01*
X186200Y204000D01*
X169500D01*
X167500Y206000D01*
X152082D01*
X150632Y204550D01*
X135250D01*
X125525Y194825D01*
X105836D01*
X100160Y200501D01*
X88578D01*
X86479Y202600D01*
X76861D01*
X73211Y206250D01*
X70461D01*
X60030Y216681D01*
X55991D01*
X54100Y218572D01*
Y228200D01*
X41250Y241050D01*
X38950D01*
X37900Y240000D01*
G01X352600Y220750D02*
X347589D01*
X346739Y221600D01*
X344039D01*
X338600Y227039D01*
Y231339D01*
X330039Y239900D01*
X325361D01*
X323125Y237664D01*
Y236125D01*
X317300Y230300D01*
X305461D01*
X301475Y226314D01*
Y221799D01*
X295376Y215700D01*
X285800D01*
X285000Y214900D01*
X274514D01*
X268639Y220775D01*
X236509D01*
X225634Y209900D01*
X190261D01*
X185661Y205300D01*
X170039D01*
X168039Y207300D01*
X151543D01*
X150093Y205850D01*
X134711D01*
X124986Y196125D01*
X106375D01*
X100699Y201801D01*
X89117D01*
X87018Y203900D01*
X77400D01*
X73750Y207550D01*
X71000D01*
X60569Y217981D01*
X56530D01*
X55400Y219111D01*
Y228739D01*
X41789Y242350D01*
X39050D01*
X37900Y243500D01*
G01Y254000D02*
X39000Y255100D01*
X45900D01*
X50500Y250500D01*
Y244404D01*
X64450Y230454D01*
Y225811D01*
X79186Y211075D01*
X103807D01*
X111682Y203200D01*
X119709D01*
X131174Y214665D01*
Y214666D01*
X132608Y216100D01*
X223065D01*
X235540Y228575D01*
X276129D01*
X282804Y221900D01*
X293439D01*
X295900Y224361D01*
Y229300D01*
X307100Y240500D01*
X322496D01*
X324396Y242400D01*
X354800D01*
X361227Y235973D01*
Y227500D01*
G01X37900Y257500D02*
X39000Y256400D01*
X46439D01*
X51800Y251039D01*
Y244943D01*
X65750Y230993D01*
Y226350D01*
X79725Y212375D01*
X104346D01*
X112221Y204500D01*
X119170D01*
X129874Y215204D01*
Y215205D01*
X132069Y217400D01*
X222526D01*
X235001Y229875D01*
X276668D01*
X283343Y223200D01*
X292900D01*
X294600Y224900D01*
Y229839D01*
X306561Y241800D01*
X321957D01*
X323857Y243700D01*
X355339D01*
X362527Y236512D01*
Y227500D01*
G01X55720Y184380D02*
X56900Y183200D01*
Y181661D01*
X65711Y172850D01*
X90311D01*
X95530Y167631D01*
Y160170D01*
X106600Y149100D01*
X108639D01*
X110100Y150561D01*
Y154350D01*
X111300Y155550D01*
X112950D01*
X117050Y151450D01*
X153789D01*
X157539Y155200D01*
X166539D01*
X174710Y163371D01*
X181710D01*
X191439Y173100D01*
X201339D01*
X202239Y174000D01*
X223086D01*
X236886Y187800D01*
X242900D01*
X244650Y189550D01*
X250434D01*
X254594Y193710D01*
X299010D01*
X302800Y197500D01*
X309800D01*
X312600Y200300D01*
X313700D01*
X315000Y199000D01*
X318700D01*
X320000Y200300D01*
X323200D01*
G01X59379Y184380D02*
X58200Y183201D01*
Y182200D01*
X59155Y181245D01*
X60343D01*
X61297Y180291D01*
Y179103D01*
X62252Y178148D01*
X63440D01*
X64394Y177194D01*
Y176006D01*
X66250Y174150D01*
X90850D01*
X96830Y168170D01*
Y160709D01*
X107139Y150400D01*
X108100D01*
X108800Y151100D01*
Y154889D01*
X110761Y156850D01*
X113489D01*
X117589Y152750D01*
X153250D01*
X157000Y156500D01*
X159770D01*
X160610Y157340D01*
X161960D01*
X162800Y156500D01*
X166000D01*
X174171Y164671D01*
X181171D01*
X190900Y174400D01*
X200800D01*
X201700Y175300D01*
X209407D01*
X210247Y176140D01*
X211597D01*
X212437Y175300D01*
X213787D01*
X214627Y176140D01*
X215977D01*
X216817Y175300D01*
X218167D01*
X219007Y176140D01*
X220357D01*
X221197Y175300D01*
X222547D01*
X236347Y189100D01*
X242361D01*
X244111Y190850D01*
X249895D01*
X254055Y195010D01*
X298471D01*
X302261Y198800D01*
X309261D01*
X312061Y201600D01*
X314239D01*
X315539Y200300D01*
X318161D01*
X319461Y201600D01*
X323200D01*
G01X326125Y206525D02*
X319525D01*
X318400Y205400D01*
X310900D01*
X307000Y201500D01*
X300661D01*
X297921Y198760D01*
X252501D01*
X248341Y194600D01*
X236543D01*
X227243Y185300D01*
X226539D01*
X225800Y186039D01*
Y189539D01*
X224139Y191200D01*
X220600D01*
X219200Y189800D01*
Y186461D01*
X220200Y185461D01*
Y184039D01*
X219080Y182919D01*
X219079Y182920D01*
X217419D01*
X216409Y183930D01*
X213330D01*
X209700Y180300D01*
X193750D01*
X191600Y178150D01*
X189350D01*
X188000Y179500D01*
Y180539D01*
X186289Y182250D01*
X183911D01*
X182700Y181039D01*
Y178500D01*
X181500Y177300D01*
X180500D01*
X179800Y178000D01*
Y180105D01*
X177905Y182000D01*
X174500D01*
X169475Y176975D01*
X164636D01*
X162700Y175039D01*
Y170539D01*
X162369Y170208D01*
X160631D01*
X159800Y171039D01*
Y176200D01*
X158500Y177500D01*
X156604D01*
X153450Y174346D01*
Y158450D01*
X151500Y156500D01*
X124839D01*
X123500Y157839D01*
Y160549D01*
X120249Y163800D01*
X118039D01*
X116905Y164934D01*
Y167144D01*
X114659Y169390D01*
X112945D01*
X106764Y163208D01*
X106130D01*
X105489Y163849D01*
Y166150D01*
X109800Y170461D01*
Y173539D01*
X108464Y174875D01*
X105461D01*
X100886Y170300D01*
X100039D01*
X99050Y171289D01*
Y173789D01*
X91639Y181200D01*
X78861D01*
X75961Y178300D01*
X73288D01*
X63388Y188200D01*
X58039D01*
X55864Y190375D01*
X52895D01*
X51860Y191410D01*
G01X326125Y205225D02*
X320064D01*
X318939Y204100D01*
X311439D01*
X307539Y200200D01*
X301200D01*
X298460Y197460D01*
X253040D01*
X248880Y193300D01*
X237082D01*
X227782Y184000D01*
X226000D01*
X224500Y185500D01*
Y189000D01*
X223600Y189900D01*
X221139D01*
X220500Y189261D01*
Y187000D01*
X221500Y186000D01*
Y183499D01*
X219619Y181618D01*
X218542D01*
X218540Y181620D01*
X216880D01*
X215870Y182630D01*
X213869D01*
X210239Y179000D01*
X208899D01*
X208059Y178160D01*
X206709D01*
X205869Y179000D01*
X204519D01*
X203679Y178160D01*
X202329D01*
X201489Y179000D01*
X194289D01*
X192139Y176850D01*
X188811D01*
X186700Y178961D01*
Y180000D01*
X185750Y180950D01*
X184450D01*
X184000Y180500D01*
Y177961D01*
X182039Y176000D01*
X179961D01*
X178500Y177461D01*
Y179566D01*
X177366Y180700D01*
X175039D01*
X170014Y175675D01*
X165175D01*
X164000Y174500D01*
Y170000D01*
X162908Y168908D01*
X160092D01*
X158500Y170500D01*
Y175661D01*
X157961Y176200D01*
X157143D01*
X154750Y173807D01*
Y163950D01*
X155590Y163110D01*
Y161760D01*
X154750Y160920D01*
Y157911D01*
X152039Y155200D01*
X124300D01*
X122200Y157300D01*
Y160010D01*
X119710Y162500D01*
X117500D01*
X115605Y164395D01*
Y166605D01*
X115604D01*
X114120Y168090D01*
X113484D01*
X107303Y161908D01*
X105591D01*
X104189Y163310D01*
Y166689D01*
X108500Y171000D01*
Y173000D01*
X107925Y173575D01*
X106000D01*
X101425Y169000D01*
X99500D01*
X97750Y170750D01*
Y173250D01*
X96470Y174530D01*
X95282D01*
X94328Y175484D01*
Y176672D01*
X91100Y179900D01*
X79400D01*
X76500Y177000D01*
X72749D01*
X68894Y180855D01*
X67706D01*
X66752Y181809D01*
Y182997D01*
X62849Y186900D01*
X57500D01*
X55325Y189075D01*
X53295D01*
X51860Y187640D01*
G01X336750Y95704D02*
X336246Y95200D01*
X334813D01*
X330988Y91375D01*
X329449D01*
X326525Y88451D01*
Y86864D01*
X321211Y81550D01*
X317246D01*
X306547Y70851D01*
X302612D01*
X294424Y62663D01*
Y59102D01*
X289272Y53950D01*
X227950D01*
X216600Y65300D01*
X203861D01*
X195600Y57039D01*
Y55300D01*
X194700Y54400D01*
G01X336750Y93500D02*
X336350Y93900D01*
X335352D01*
X331527Y90075D01*
X329988D01*
X327825Y87912D01*
Y86325D01*
X321750Y80250D01*
X317785D01*
X307086Y69551D01*
X303151D01*
X295724Y62124D01*
Y58563D01*
X289811Y52650D01*
X227411D01*
X216061Y64000D01*
X204400D01*
X196900Y56500D01*
Y55200D01*
X197700Y54400D01*
G01X346596Y115163D02*
X345659Y116100D01*
X342139D01*
X336753Y110714D01*
Y100186D01*
X339800Y97139D01*
Y89861D01*
X324439Y74500D01*
X318839D01*
X309339Y65000D01*
X305100D01*
X300275Y60175D01*
Y56636D01*
X290939Y47300D01*
X224600D01*
X212450Y59450D01*
X210000D01*
X207700Y57150D01*
Y55900D01*
X208700Y54900D01*
G01X346596Y118163D02*
X345833Y117400D01*
X341600D01*
X335453Y111253D01*
Y99647D01*
X338500Y96600D01*
Y90400D01*
X323900Y75800D01*
X318300D01*
X308800Y66300D01*
X304561D01*
X298975Y60714D01*
Y57175D01*
X290400Y48600D01*
X225139D01*
X212989Y60750D01*
X209461D01*
X206400Y57689D01*
Y56000D01*
X205300Y54900D01*
G01X209259Y117430D02*
X210439Y116250D01*
X213750D01*
X215700Y118200D01*
X257773D01*
X263173Y123600D01*
X289493D01*
X293639Y127746D01*
Y128713D01*
X295351Y130425D01*
X296386D01*
X298300Y132339D01*
Y137343D01*
X318627Y157670D01*
G01X209259Y113771D02*
X210438Y114950D01*
X214289D01*
X216239Y116900D01*
X258312D01*
X263712Y122300D01*
X290032D01*
X294939Y127207D01*
Y128174D01*
X295890Y129125D01*
X296925D01*
X299600Y131800D01*
Y136804D01*
X319547Y156751D01*
G01X324350Y184800D02*
X323139D01*
X321439Y186500D01*
X318880D01*
X318040Y185660D01*
X316690D01*
X315850Y186500D01*
X314500D01*
X313000Y185000D01*
X296500D01*
X294587Y186913D01*
X290228D01*
X289215Y185900D01*
X272039D01*
X271264Y185125D01*
X250596D01*
X249756Y184285D01*
X248406D01*
X247566Y185125D01*
X246216D01*
X242784Y181693D01*
X240993D01*
X239900Y180600D01*
G01X240119Y183993D02*
X241119Y182993D01*
X242245D01*
X245677Y186425D01*
X270725D01*
X271500Y187200D01*
X288676D01*
X289689Y188213D01*
X295126D01*
X297039Y186300D01*
X312461D01*
X313961Y187800D01*
X321978D01*
X323678Y186100D01*
X324350D01*
G01X320992Y112180D02*
X320897D01*
X306301Y97584D01*
Y93737D01*
X300339Y87775D01*
X299043D01*
X296793Y85525D01*
X292525D01*
X276100Y69100D01*
X257357D01*
X255797Y67540D01*
Y66352D01*
X254843Y65398D01*
X253655D01*
X252600Y64343D01*
Y58800D01*
X253500Y57900D01*
G01X333434Y106668D02*
X332566Y105800D01*
X329961D01*
X326625Y102464D01*
Y99826D01*
X323199Y96400D01*
X316061D01*
X311700Y92039D01*
Y90239D01*
X295700Y74239D01*
Y71700D01*
X286449Y62449D01*
X262311D01*
X259900Y60038D01*
Y58700D01*
X259000Y57800D01*
G01X333313Y103693D02*
X332506Y104500D01*
X330500D01*
X327925Y101925D01*
Y99287D01*
X323738Y95100D01*
X316600D01*
X313000Y91500D01*
Y89700D01*
X307491Y84191D01*
Y83003D01*
X306537Y82049D01*
X305349D01*
X304394Y81094D01*
Y79906D01*
X303440Y78952D01*
X302252D01*
X301297Y77997D01*
Y76809D01*
X300343Y75855D01*
X299155D01*
X297000Y73700D01*
Y71161D01*
X286988Y61149D01*
X262850D01*
X261200Y59499D01*
Y58600D01*
X262000Y57800D01*
G01X319096Y113300D02*
Y112218D01*
X305001Y98123D01*
Y94276D01*
X299800Y89075D01*
X298504D01*
X296254Y86825D01*
X291986D01*
X275561Y70400D01*
X256818D01*
X251300Y64882D01*
Y58700D01*
X250500Y57900D01*
G54D15*
X804032Y57032D03*
G54D25*
G01X615852Y19807D02*
X615652Y20007D01*
X610800D01*
X602250Y28557D01*
Y36950D01*
X582800Y56400D01*
X580400D01*
X579600Y55600D01*
Y47000D01*
X578800Y46200D01*
X533900D01*
X533100Y47000D01*
Y56200D01*
X531425Y57875D01*
X450425D01*
X429500Y78800D01*
X399200D01*
X397350Y80650D01*
G01X615907Y24856D02*
X615358Y24307D01*
X608400D01*
X603960Y28747D01*
Y39040D01*
X582651Y60349D01*
X576600D01*
X575800Y59549D01*
Y50800D01*
X575000Y50000D01*
X536950D01*
X536150Y50800D01*
Y59725D01*
X535550Y60325D01*
X451939D01*
X450505Y61759D01*
Y61760D01*
X431765Y80500D01*
X401200D01*
G01X623555Y25107D02*
X623505Y25157D01*
Y27102D01*
X620800Y29807D01*
Y36894D01*
X619636Y38058D01*
X619576D01*
X587485Y70149D01*
X573985D01*
X571934Y72200D01*
X565800D01*
X564700Y71100D01*
Y66500D01*
X563900Y65700D01*
X547000D01*
X546200Y66500D01*
Y69399D01*
X545450Y70149D01*
X455976D01*
X436725Y89400D01*
X417500D01*
X416500Y90400D01*
Y98800D01*
G01X619730Y24864D02*
Y25577D01*
X616700Y28607D01*
X614400D01*
X612700Y30307D01*
Y32452D01*
X612719Y32471D01*
Y37681D01*
X585151Y65249D01*
X570650D01*
X569900Y64499D01*
Y61100D01*
X569100Y60300D01*
X562757D01*
X561957Y59500D01*
Y56950D01*
X561207Y56200D01*
X558207D01*
X557457Y56950D01*
Y59450D01*
X556707Y60200D01*
X553707D01*
X552957Y59450D01*
Y56950D01*
X552207Y56200D01*
X549207D01*
X548457Y56950D01*
Y59400D01*
X547657Y60200D01*
X541900D01*
X541100Y61000D01*
Y64499D01*
X540350Y65249D01*
X536549D01*
X536525Y65225D01*
X453970D01*
X435295Y83900D01*
X410400D01*
G01X619607Y19807D02*
X619400D01*
X617882Y21325D01*
Y25392D01*
X616367Y26907D01*
X608600D01*
X605400Y30107D01*
Y41300D01*
X583901Y62799D01*
X573500D01*
X572700Y61999D01*
Y54300D01*
X571900Y53500D01*
X539400D01*
X538600Y54300D01*
Y62025D01*
X537850Y62775D01*
X452955D01*
X433730Y82000D01*
X406200D01*
X405500Y82700D01*
G01X623532Y20007D02*
X623526D01*
X621705Y21828D01*
Y25502D01*
X617000Y30207D01*
Y37168D01*
X601234Y52934D01*
X586470Y67699D01*
X572970D01*
X570919Y69750D01*
X568250D01*
X567200Y68700D01*
Y63700D01*
X566400Y62900D01*
X544500D01*
X543700Y63700D01*
Y66949D01*
X542950Y67699D01*
X454961D01*
X436960Y85700D01*
X416900D01*
G01X627255Y25107D02*
X626700Y25662D01*
Y36167D01*
X618532Y44335D01*
Y46032D01*
X614867Y49697D01*
Y50758D01*
X615675Y51565D01*
Y52625D01*
X614613Y53687D01*
X613553D01*
X612745Y52880D01*
X611685D01*
X610623Y53942D01*
Y55002D01*
X611431Y55809D01*
Y56869D01*
X610369Y57931D01*
X609309D01*
X608501Y57124D01*
X607441D01*
X587465Y77100D01*
X585015D01*
X584265Y76350D01*
Y75799D01*
X583515Y75049D01*
X582015D01*
X581265Y75799D01*
Y76350D01*
X580515Y77100D01*
X579015D01*
X578265Y76350D01*
Y75799D01*
X577515Y75049D01*
X576015D01*
X575265Y75799D01*
Y76350D01*
X574515Y77100D01*
X547666D01*
X546916Y76350D01*
Y75799D01*
X546166Y75049D01*
X544666D01*
X543916Y75799D01*
Y76350D01*
X543166Y77100D01*
X541666D01*
X540916Y76350D01*
Y75799D01*
X540166Y75049D01*
X538666D01*
X537916Y75799D01*
Y76350D01*
X537166Y77100D01*
X535666D01*
X534916Y76350D01*
Y75799D01*
X534166Y75049D01*
X532666D01*
X531916Y75799D01*
Y76350D01*
X531166Y77100D01*
X511114D01*
X510364Y76350D01*
Y75799D01*
X509614Y75049D01*
X508114D01*
X507364Y75799D01*
Y76350D01*
X506614Y77100D01*
X505114D01*
X504364Y76350D01*
Y75799D01*
X503614Y75049D01*
X502114D01*
X501364Y75799D01*
Y76350D01*
X500614Y77100D01*
X499114D01*
X498364Y76350D01*
Y75799D01*
X497614Y75049D01*
X496114D01*
X495364Y75799D01*
Y76350D01*
X494614Y77100D01*
X475005D01*
X474255Y76350D01*
Y75799D01*
X473505Y75049D01*
X472005D01*
X471255Y75799D01*
Y76350D01*
X470505Y77100D01*
X469005D01*
X468255Y76350D01*
Y75799D01*
X467505Y75049D01*
X466005D01*
X465255Y75799D01*
Y76350D01*
X464505Y77100D01*
X463005D01*
X462255Y76350D01*
Y75799D01*
X461505Y75049D01*
X460005D01*
X459255Y75799D01*
Y76350D01*
X458505Y77100D01*
X456055D01*
X439855Y93300D01*
X432800D01*
X429750Y96350D01*
G01X627231Y19907D02*
Y19922D01*
X625480Y21673D01*
Y27687D01*
X621950Y31217D01*
Y39149D01*
X588501Y72599D01*
X575000D01*
X572949Y74650D01*
X549350D01*
X547299Y72599D01*
X529028D01*
X528278Y73349D01*
Y73900D01*
X527528Y74650D01*
X526028D01*
X525278Y73900D01*
Y73349D01*
X524528Y72599D01*
X523028D01*
X522278Y73349D01*
Y73900D01*
X521528Y74650D01*
X520028D01*
X519278Y73900D01*
Y73349D01*
X518528Y72599D01*
X517028D01*
X516278Y73349D01*
Y73900D01*
X515528Y74650D01*
X514028D01*
X513278Y73900D01*
Y73349D01*
X512528Y72599D01*
X493082D01*
X492332Y73349D01*
Y73900D01*
X491582Y74650D01*
X490082D01*
X489332Y73900D01*
Y73349D01*
X488582Y72599D01*
X487082D01*
X486332Y73349D01*
Y73900D01*
X485582Y74650D01*
X484082D01*
X483332Y73900D01*
Y73349D01*
X482582Y72599D01*
X481082D01*
X480332Y73349D01*
Y73900D01*
X479582Y74650D01*
X478082D01*
X477332Y73900D01*
Y73349D01*
X476582Y72599D01*
X456991D01*
X440045Y89545D01*
Y89555D01*
X437700Y91900D01*
X425600D01*
G01X631000Y20107D02*
Y20203D01*
X629032Y22171D01*
Y23143D01*
X629030Y23145D01*
Y26777D01*
X628300Y27507D01*
Y36822D01*
X620250Y44872D01*
Y53450D01*
X619700Y54000D01*
X617800D01*
X609899Y61901D01*
X608839D01*
X608016Y61078D01*
X606956D01*
X605894Y62140D01*
Y63200D01*
X606717Y64023D01*
Y65083D01*
X605655Y66145D01*
X604595D01*
X603772Y65322D01*
X602712D01*
X601650Y66384D01*
Y67444D01*
X602473Y68267D01*
Y69327D01*
X601411Y70389D01*
X600351D01*
X599528Y69566D01*
X598468D01*
X597406Y70628D01*
Y71688D01*
X598229Y72511D01*
Y73571D01*
X597167Y74633D01*
X596107D01*
X595284Y73810D01*
X594224D01*
X593162Y74872D01*
Y75932D01*
X593985Y76755D01*
Y77815D01*
X592250Y79550D01*
X457070D01*
X441820Y94800D01*
X434500D01*
X431700Y97600D01*
G01X609500Y254900D02*
X608212Y253612D01*
Y251320D01*
X610382Y249150D01*
X615950D01*
X618550Y246550D01*
Y226750D01*
X609310Y217510D01*
X603280D01*
X586170Y200400D01*
X564699D01*
X562599Y198300D01*
X466834D01*
X460234Y204900D01*
X449800D01*
X448461Y203561D01*
X431961D01*
X429200Y200800D01*
X428450D01*
G01Y199150D02*
X429884D01*
X432645Y201911D01*
X449145D01*
X450484Y203250D01*
X459550D01*
X466150Y196650D01*
X563283D01*
X565383Y198750D01*
X586854D01*
X603964Y215860D01*
X609994D01*
X611319Y217185D01*
X612577D01*
X614168Y218776D01*
Y220034D01*
X615759Y221625D01*
X617018D01*
X618609Y223216D01*
Y224475D01*
X620200Y226066D01*
Y233040D01*
X621090Y233930D01*
Y236180D01*
X620200Y237070D01*
Y240742D01*
X621090Y241632D01*
Y243882D01*
X620200Y244772D01*
Y247234D01*
X616634Y250800D01*
X611066D01*
X609937Y251929D01*
Y252106D01*
G01X608996Y270206D02*
Y270138D01*
X609761Y269373D01*
Y260661D01*
X608000Y258900D01*
X605989D01*
X601375Y254286D01*
Y244959D01*
X606725Y239609D01*
Y234005D01*
X607615Y233115D01*
Y230865D01*
X606725Y229975D01*
Y227725D01*
X604017Y225017D01*
X598275D01*
X590608Y217350D01*
X586414D01*
X583809Y219955D01*
X581079D01*
X580200Y219076D01*
Y216200D01*
X577900Y213900D01*
X575024D01*
X569199Y208075D01*
X562260D01*
X559684Y205499D01*
X545075D01*
X542499Y208075D01*
X533409D01*
X531723Y206389D01*
X527877D01*
X526466Y207800D01*
X524861D01*
X523450Y206389D01*
X519311D01*
X517625Y208075D01*
X515275D01*
X512699Y205499D01*
X504997D01*
X503921Y206575D01*
X500391D01*
X499315Y205499D01*
X495697D01*
X494621Y206575D01*
X491091D01*
X490015Y205499D01*
X486397D01*
X485321Y206575D01*
X481791D01*
X480715Y205499D01*
X472567D01*
X469857Y208209D01*
X468598D01*
X467007Y209800D01*
Y211059D01*
X465416Y212650D01*
X457605D01*
X456715Y211760D01*
X454465D01*
X453575Y212650D01*
X451325D01*
X450435Y211760D01*
X448185D01*
X447295Y212650D01*
X445045D01*
X444155Y211760D01*
X441905D01*
X441015Y212650D01*
X432564D01*
X431674Y211760D01*
X429424D01*
X428534Y212650D01*
X426284D01*
X424667Y211033D01*
G01X423500Y212200D02*
X425600Y214300D01*
X466100D01*
X473251Y207149D01*
X480031D01*
X481107Y208225D01*
X486005D01*
X487081Y207149D01*
X489331D01*
X490407Y208225D01*
X495305D01*
X496381Y207149D01*
X498631D01*
X499707Y208225D01*
X504605D01*
X505681Y207149D01*
X512015D01*
X514591Y209725D01*
X518309D01*
X519995Y208039D01*
X522766D01*
X524177Y209450D01*
X527150D01*
X528561Y208039D01*
X531039D01*
X532725Y209725D01*
X543183D01*
X545759Y207149D01*
X559000D01*
X561576Y209725D01*
X568515D01*
X574340Y215550D01*
X577216D01*
X578550Y216884D01*
Y219760D01*
X580395Y221605D01*
X584493D01*
X587098Y219000D01*
X589924D01*
X597591Y226667D01*
X603333D01*
X605075Y228409D01*
Y238925D01*
X599725Y244275D01*
Y254970D01*
X605305Y260550D01*
X607316D01*
X608111Y261345D01*
Y268389D01*
X607271Y269229D01*
Y271121D01*
X609039Y272889D01*
X609896D01*
G01X606700Y255600D02*
X606562Y255462D01*
Y248338D01*
X607750Y247150D01*
X610750D01*
X612800Y245100D01*
Y225287D01*
X607773Y220260D01*
X599742D01*
X588982Y209500D01*
X578700D01*
X572875Y203675D01*
X564084D01*
X561508Y201099D01*
X543251D01*
X541000Y203350D01*
X537774D01*
X535523Y201099D01*
X467467D01*
X461316Y207250D01*
X447984D01*
X446784Y206050D01*
X443316D01*
X442116Y207250D01*
X440184D01*
X438958Y206024D01*
X434742D01*
X433216Y207550D01*
X430510D01*
X428984Y206024D01*
X426271D01*
G01X604074Y254394D02*
X604912Y253556D01*
Y247654D01*
X607066Y245500D01*
X610066D01*
X611150Y244416D01*
Y242166D01*
X610260Y241276D01*
Y239026D01*
X611150Y238136D01*
Y225971D01*
X607089Y221910D01*
X599058D01*
X588298Y211150D01*
X584296D01*
X583406Y212040D01*
X581156D01*
X580266Y211150D01*
X578016D01*
X572191Y205325D01*
X563400D01*
X560824Y202749D01*
X543935D01*
X541684Y205000D01*
X537090D01*
X534839Y202749D01*
X524851D01*
X523961Y203639D01*
X521839D01*
X520949Y202749D01*
X518751D01*
X517861Y203639D01*
X515739D01*
X514849Y202749D01*
X503851D01*
X502961Y203639D01*
X501639D01*
X500749Y202749D01*
X485251D01*
X484300Y203700D01*
X482922D01*
X481971Y202749D01*
X468151D01*
X462000Y208900D01*
X447300D01*
X446100Y207700D01*
X444000D01*
X442800Y208900D01*
X439500D01*
X438274Y207674D01*
X435426D01*
X433900Y209200D01*
X429826D01*
X428300Y207674D01*
X426271D01*
G01X605100Y270100D02*
X604250Y269250D01*
Y266196D01*
X605462Y264984D01*
Y262462D01*
X601786Y258786D01*
Y258753D01*
X599781Y256748D01*
X599748D01*
X598250Y255250D01*
Y243350D01*
X594854Y239954D01*
Y238896D01*
X598934Y234816D01*
Y232600D01*
X596694Y230360D01*
X594478D01*
X590398Y234440D01*
X589340D01*
X587429Y232529D01*
Y231471D01*
X591859Y227041D01*
Y224825D01*
X589619Y222585D01*
X587403D01*
X582973Y227015D01*
X581915D01*
X567375Y212475D01*
X563789D01*
X562073Y214191D01*
Y217600D01*
X561473Y218200D01*
X559773D01*
X559073Y217500D01*
Y214191D01*
X557357Y212475D01*
X509709D01*
X508209Y210975D01*
X473800D01*
X467725Y217050D01*
X425069D01*
X421717Y213698D01*
G01X421300Y215615D02*
X424385Y218700D01*
X437580D01*
X438470Y219590D01*
X440720D01*
X441610Y218700D01*
X443860D01*
X444750Y219590D01*
X447000D01*
X447890Y218700D01*
X468409D01*
X474484Y212625D01*
X483924D01*
X484814Y213515D01*
X487064D01*
X487954Y212625D01*
X490204D01*
X491094Y213515D01*
X493344D01*
X494234Y212625D01*
X507525D01*
X509025Y214125D01*
X556673D01*
X557423Y214875D01*
Y218184D01*
X559089Y219850D01*
X562157D01*
X563723Y218284D01*
Y214875D01*
X564473Y214125D01*
X566691D01*
X569249Y216683D01*
Y217942D01*
X570840Y219533D01*
X572099D01*
X573690Y221124D01*
Y222382D01*
X575108Y223800D01*
X576366D01*
X581231Y228665D01*
X583657D01*
X588087Y224235D01*
X588935D01*
X590209Y225509D01*
Y226357D01*
X585779Y230787D01*
Y233213D01*
X588656Y236090D01*
X591082D01*
X595162Y232010D01*
X596010D01*
X597284Y233284D01*
Y234132D01*
X593204Y238212D01*
Y240638D01*
X596600Y244034D01*
Y255934D01*
X599064Y258398D01*
X599097D01*
X600136Y259437D01*
Y259470D01*
X603812Y263146D01*
Y264300D01*
X602600Y265512D01*
Y270600D01*
X604967Y272967D01*
X605065D01*
G01X638400Y20607D02*
X636532Y22475D01*
Y23443D01*
X636530Y23445D01*
Y28810D01*
X637000Y29280D01*
Y39642D01*
X632700Y43942D01*
Y57194D01*
X597944Y91950D01*
X458861D01*
X448811Y102000D01*
X436544D01*
X435672Y102872D01*
G01X634555Y25307D02*
Y28462D01*
X635500Y29407D01*
Y38234D01*
X627600Y46134D01*
Y58829D01*
X600903Y85525D01*
X598681D01*
X596557Y87649D01*
X596026D01*
X595175Y88500D01*
X593300D01*
X591738Y86938D01*
X586100D01*
X585300Y87738D01*
Y88600D01*
X584500Y89400D01*
X582000D01*
X581200Y88600D01*
Y87738D01*
X580400Y86938D01*
X552162D01*
X550407Y88693D01*
X548324D01*
X546569Y86938D01*
X538662D01*
X537200Y88400D01*
X535100D01*
X533638Y86938D01*
X532062D01*
X531031Y87969D01*
X529263D01*
X528232Y86938D01*
X514035D01*
X513285Y87688D01*
Y88550D01*
X512535Y89300D01*
X511035D01*
X510285Y88550D01*
Y87688D01*
X509535Y86938D01*
X495327D01*
X492765Y89500D01*
X457846D01*
X447246Y100100D01*
X436817D01*
X435108Y101809D01*
G01X638290Y25674D02*
X638305Y25689D01*
Y40802D01*
X635300Y43807D01*
Y58059D01*
X630255Y63104D01*
Y64164D01*
X630511Y64420D01*
Y65480D01*
X629449Y66542D01*
X628389D01*
X628133Y66286D01*
X627073D01*
X626011Y67348D01*
Y68408D01*
X626267Y68664D01*
Y69724D01*
X625205Y70786D01*
X624145D01*
X623889Y70530D01*
X622829D01*
X621767Y71592D01*
Y72652D01*
X622023Y72908D01*
Y73968D01*
X620961Y75030D01*
X619901D01*
X619645Y74774D01*
X618585D01*
X617523Y75836D01*
Y76896D01*
X617779Y77152D01*
Y78212D01*
X616717Y79274D01*
X615657D01*
X615401Y79018D01*
X614341D01*
X598958Y94401D01*
X596930D01*
X596929Y94400D01*
X459876D01*
X450476Y103800D01*
X446900D01*
G01X634757Y20207D02*
X634557Y20407D01*
X634546D01*
X632782Y22171D01*
Y23443D01*
X632780Y23445D01*
Y27427D01*
X631500Y28707D01*
Y39707D01*
X625150Y46057D01*
Y57813D01*
X599888Y83075D01*
X597666D01*
X596253Y84488D01*
X494312D01*
X491750Y87050D01*
X489661D01*
X488911Y86300D01*
Y85350D01*
X488161Y84600D01*
X486661D01*
X485911Y85350D01*
Y86300D01*
X485161Y87050D01*
X483661D01*
X482911Y86300D01*
Y85350D01*
X482161Y84600D01*
X480661D01*
X479911Y85350D01*
Y86300D01*
X479161Y87050D01*
X477661D01*
X476911Y86300D01*
Y85350D01*
X476161Y84600D01*
X474661D01*
X473911Y85350D01*
Y86300D01*
X473161Y87050D01*
X471661D01*
X470911Y86300D01*
Y85350D01*
X470161Y84600D01*
X468661D01*
X467911Y85350D01*
Y86300D01*
X467161Y87050D01*
X465661D01*
X464911Y86300D01*
Y85350D01*
X464161Y84600D01*
X462661D01*
X461911Y85350D01*
Y86300D01*
X461161Y87050D01*
X456831D01*
X445481Y98400D01*
X435400D01*
G01X630955Y25207D02*
Y26952D01*
X629900Y28007D01*
Y38007D01*
X622700Y45207D01*
Y56798D01*
X620766Y58732D01*
X619706D01*
X618668Y57693D01*
X617608D01*
X616546Y58755D01*
Y59815D01*
X617584Y60854D01*
Y61914D01*
X616522Y62976D01*
X615462D01*
X614424Y61937D01*
X613364D01*
X612302Y62999D01*
Y64059D01*
X613340Y65098D01*
Y66158D01*
X612278Y67220D01*
X611218D01*
X610180Y66181D01*
X609120D01*
X608058Y67243D01*
Y68303D01*
X609096Y69342D01*
Y70402D01*
X608034Y71464D01*
X606974D01*
X605936Y70425D01*
X604876D01*
X603814Y71487D01*
Y72547D01*
X604852Y73586D01*
Y74646D01*
X603790Y75708D01*
X602730D01*
X601692Y74669D01*
X600632D01*
X599570Y75731D01*
Y76791D01*
X600608Y77830D01*
Y78890D01*
X598873Y80625D01*
X596651D01*
X595276Y82000D01*
X458085D01*
X443485Y96600D01*
X435850D01*
X435600Y96850D01*
G01X655700Y20225D02*
X657844Y18081D01*
X666374D01*
X669420Y21127D01*
Y58680D01*
X613100Y115000D01*
X467200D01*
X465200Y117000D01*
X449267D01*
X441000Y125267D01*
G01X642451Y20707D02*
X642346D01*
X640282Y22771D01*
Y27025D01*
X639924Y27383D01*
Y42383D01*
X637725Y44582D01*
Y47500D01*
X637750Y47525D01*
Y61709D01*
X637129Y62329D01*
X636829Y62629D01*
Y62630D01*
X615865Y83594D01*
X614805D01*
X614549Y83338D01*
X613489D01*
X612427Y84400D01*
Y85460D01*
X612683Y85716D01*
Y86776D01*
X611621Y87838D01*
X610561D01*
X610305Y87582D01*
X609245D01*
X608183Y88644D01*
Y89704D01*
X608439Y89960D01*
Y91020D01*
X607377Y92082D01*
X606317D01*
X606061Y91826D01*
X605001D01*
X603939Y92888D01*
Y93948D01*
X604195Y94204D01*
Y95264D01*
X602459Y97000D01*
X460741D01*
X452041Y105700D01*
X446700D01*
G01X441200Y109300D02*
X455372D01*
X457645Y107026D01*
X462771Y101900D01*
X604489D01*
X634856Y71533D01*
X635916D01*
X636476Y72093D01*
X637536D01*
X638598Y71031D01*
Y69971D01*
X638038Y69411D01*
Y68351D01*
X639100Y67289D01*
X640160D01*
X640720Y67849D01*
X641780D01*
X642842Y66787D01*
Y65727D01*
X642282Y65167D01*
Y64107D01*
X643344Y63045D01*
X644404D01*
X644964Y63605D01*
X646024D01*
X647086Y62543D01*
Y61483D01*
X646526Y60923D01*
Y59863D01*
X648600Y57789D01*
Y41207D01*
X653900Y35907D01*
Y26899D01*
X655576Y25223D01*
X655602D01*
G01X663202Y25973D02*
X662934D01*
X659900Y29007D01*
Y39100D01*
X658312Y40688D01*
Y59012D01*
X628174Y89150D01*
X627114D01*
X626173Y88209D01*
X625113D01*
X624051Y89271D01*
Y90331D01*
X624992Y91272D01*
Y92332D01*
X623930Y93394D01*
X622870D01*
X621929Y92453D01*
X620869D01*
X619807Y93515D01*
Y94575D01*
X620748Y95516D01*
Y96576D01*
X619686Y97638D01*
X618626D01*
X617685Y96697D01*
X616625D01*
X615563Y97759D01*
Y98819D01*
X616504Y99760D01*
Y100820D01*
X615442Y101882D01*
X614382D01*
X613441Y100941D01*
X612381D01*
X611319Y102003D01*
Y103063D01*
X612260Y104004D01*
Y105064D01*
X610524Y106800D01*
X464900D01*
X459200Y112500D01*
X439100D01*
X438700Y112900D01*
G01X642246Y25807D02*
X642446Y25607D01*
X647300D01*
X652000Y30307D01*
Y34147D01*
X650240Y35907D01*
X644800D01*
X643725Y36982D01*
Y59199D01*
X603474Y99450D01*
X461756D01*
X453206Y108000D01*
X441200D01*
G01X439995Y110895D02*
X457241D01*
X463786Y104350D01*
X605504D01*
X625960Y83894D01*
X627020D01*
X627961Y84835D01*
X629021D01*
X630083Y83773D01*
Y82713D01*
X629142Y81772D01*
Y80712D01*
X630204Y79650D01*
X631264D01*
X632205Y80591D01*
X633265D01*
X634327Y79529D01*
Y78469D01*
X633386Y77528D01*
Y76468D01*
X634448Y75406D01*
X635508D01*
X636449Y76347D01*
X637509D01*
X651200Y62656D01*
Y42307D01*
X656000Y37507D01*
Y28738D01*
X658831Y25907D01*
X659400D01*
G01X442000Y117500D02*
X443900Y115600D01*
X463135D01*
X467035Y111700D01*
X610524D01*
X610525Y111701D01*
X612553D01*
X666827Y57427D01*
Y34873D01*
X667900Y33800D01*
Y22607D01*
X664524Y19231D01*
X660543D01*
X659400Y20374D01*
Y20474D01*
G01X434960Y114529D02*
X441171D01*
X441700Y114000D01*
X461200D01*
X465950Y109250D01*
X611539D01*
X664300Y56489D01*
Y54039D01*
X663550Y53289D01*
X661650D01*
X660900Y52539D01*
Y51039D01*
X661650Y50289D01*
X663550D01*
X664300Y49539D01*
Y48039D01*
X663550Y47289D01*
X661650D01*
X660900Y46539D01*
Y45039D01*
X661650Y44289D01*
X663550D01*
X664300Y43539D01*
Y34200D01*
X666403Y32097D01*
Y23810D01*
X663585Y20992D01*
X663236D01*
X663200Y20956D01*
G54D16*
G01X227870Y170252D02*
X227747Y170375D01*
X192568D01*
X182839Y160646D01*
X176346D01*
X168175Y152475D01*
X156699Y141000D01*
X143900D01*
X138600Y146300D01*
G01X726800Y95500D02*
Y95600D01*
X726100Y96300D01*
X725795D01*
X707400Y114695D01*
Y153648D01*
X718652Y164900D01*
X734682D01*
X753000Y183218D01*
Y231500D01*
X766800Y245300D01*
Y270200D01*
X749949Y287051D01*
X317200D01*
X304386Y274237D01*
X294963D01*
X282200Y287000D01*
X238500D01*
X227000Y275500D01*
G01X244800Y100700D02*
X245059Y100959D01*
X262131D01*
G01X264500Y73100D02*
X264600Y73200D01*
X269700D01*
X275200Y78700D01*
G01X275900Y88200D02*
X282000Y94300D01*
X288125D01*
X288225Y94200D01*
X288400D01*
G01X287400Y254100D02*
X275400Y242100D01*
Y237900D01*
G01X287600Y238100D02*
X297725Y248225D01*
X319294D01*
X321194Y250125D01*
X336225D01*
X349900Y263800D01*
G01X312150Y100682D02*
X312970D01*
X314888Y102600D01*
X318075D01*
X328000Y112525D01*
Y116000D01*
X331851Y119851D01*
Y121225D01*
X336256Y125630D01*
X340005D01*
X341030Y126655D01*
Y128832D01*
X342421Y130223D01*
X344023D01*
X345853Y132053D01*
Y138339D01*
X347358Y139844D01*
Y139958D01*
X348976Y141576D01*
X349400D01*
X350493Y142669D01*
Y149825D01*
X348300Y152018D01*
Y155656D01*
X348950Y156306D01*
Y156325D01*
X349975Y157350D01*
X349994D01*
X353950Y161306D01*
Y173475D01*
X353550Y173875D01*
Y177882D01*
X355092Y179424D01*
Y188103D01*
X351350Y191845D01*
Y195525D01*
X348775Y198100D01*
X342831D01*
X339864Y201067D01*
X335014D01*
X332097Y198150D01*
X326387D01*
X325081Y196844D01*
Y195971D01*
X322250Y193140D01*
X308060D01*
X305800Y195400D01*
G01X316945Y281606D02*
X320190Y284851D01*
X748504D01*
X764062Y269293D01*
Y246562D01*
X750800Y233300D01*
Y184130D01*
X733770Y167100D01*
X717740D01*
X705200Y154560D01*
Y113783D01*
X724888Y94095D01*
X725888Y93300D01*
X728600D01*
X730200Y94900D01*
G54D17*
G01X17500Y190200D02*
Y196000D01*
X25000Y203500D01*
Y258500D01*
X30500Y264000D01*
X37500D01*
G01X181000Y167500D02*
X166000D01*
X164160Y165660D01*
X162340D01*
X158500Y161820D01*
G01X288100Y99500D02*
X285505Y96905D01*
X281352D01*
X264125Y79678D01*
Y79350D01*
G01X349600Y194800D02*
X349076Y195324D01*
X343543D01*
X342319Y194100D01*
X333130D01*
X328880Y189850D01*
X328546D01*
X328446Y189750D01*
X324773D01*
X324243Y190280D01*
X308303D01*
X303500Y195083D01*
Y195400D01*
G01X355447Y146528D02*
X353492Y144573D01*
Y143546D01*
X349996Y140050D01*
X349686D01*
X348600Y138964D01*
Y135137D01*
X349491Y134246D01*
Y130191D01*
X345275Y125975D01*
Y123275D01*
X343800Y121800D01*
X338196D01*
X336200Y119804D01*
Y115122D01*
X323578Y102500D01*
X320783D01*
X317283Y99000D01*
X316300D01*
X315950Y98650D01*
G01X436600Y275000D02*
X429050Y282550D01*
X330005D01*
X324900Y277445D01*
Y276788D01*
X323612Y275500D01*
X317700D01*
X316400Y276800D01*
G01X355447Y146528D02*
X353460Y148515D01*
Y156927D01*
X355500Y158967D01*
Y169000D01*
X361500Y175000D01*
G01X361200Y178500D02*
X367041Y184341D01*
X370608D01*
X379200Y192933D01*
Y205537D01*
X384363Y210700D01*
X385089D01*
X385789Y211400D01*
G01X433129Y245783D02*
X432756Y245410D01*
Y243944D01*
X430312Y241500D01*
X402700D01*
X395100Y233900D01*
X390100D01*
X385950Y229750D01*
G01X548354Y183600D02*
X546035Y181281D01*
X520319D01*
X518200Y183400D01*
G01X548354Y183600D02*
X550654Y181300D01*
X562570D01*
X564397Y183127D01*
Y183480D01*
X564398Y183481D01*
G01X592200Y145000D02*
Y127200D01*
X593400Y126000D01*
G01X743100Y195500D02*
X730500D01*
X726700Y191700D01*
X709145D01*
X701245Y183800D01*
G54D18*
G01X117500Y146950D02*
X121042D01*
X124300Y143692D01*
Y132284D01*
X123350Y131334D01*
Y122107D01*
X128900Y116557D01*
Y101800D01*
X134100Y96600D01*
G01X276811Y263386D02*
X278824Y265399D01*
X286501D01*
X287800Y264100D01*
X296097D01*
X296811Y263386D01*
G54D19*
G01X240565Y113365D02*
X224365D01*
X219900Y108900D01*
X204500D01*
X202500Y106900D01*
X194740D01*
X186194Y98354D01*
Y92875D01*
X173869Y80550D01*
X173719D01*
X156594Y63425D01*
X141250D01*
X141000Y63675D01*
X130625D01*
X116150Y78150D01*
Y123150D01*
X118500Y125500D01*
M02*
